FILE_TYPE = MACRO_DRAWING;
SET COLOR_WIRE YELLOW;
SET COLOR_PROP ORANGE;
SET COLOR_DOT WHITE;
SET COLOR_ARC YELLOW;
SET COLOR_BODY GREEN;
SET COLOR_NOTE PURPLE;
SET PROP_DISPLAY VALUE;
SET PAGE_NUMBER P208;
FORCEADD OFFPAGE..1
(-2200 -100);
FORCEPROP 2 LAST $XR1 222 
J 0
(-2572 -100);
DISPLAY 0.638298 (-2572 -100);
PAINT MONO (-2572 -100);
FORCEPROP 2 LAST $XR0 214 
J 0
(-2452 -100);
DISPLAY 0.638298 (-2452 -100);
PAINT MONO (-2452 -100);
FORCEPROP 2 LAST CDS_LIB standard
J 0
(-2200 -100);
PAINT MONO (-2200 -100);
DISPLAY INVISIBLE (-2200 -100);
FORCEPROP 1 LAST OFFPAGE TRUE
J 0
(-1875 -225);
DISPLAY 0.872340 (-1875 -225);
PAINT GREEN (-1875 -225);
DISPLAY INVISIBLE (-1875 -225);
FORCEPROP 1 LAST COMMENT_BODY TRUE
J 0
(-2075 -200);
DISPLAY 0.872340 (-2075 -200);
PAINT GREEN (-2075 -200);
DISPLAY INVISIBLE (-2075 -200);
FORCEPROP 2 LAST PATH I1
J 0
(-2500 -50);
DISPLAY 1.021277 (-2500 -50);
DISPLAY INVISIBLE (-2500 -50);
FORCEADD Q_RES..1
(-300 3100);
FORCEPROP 1 LAST PART_NUMBER CS22002FB07
J 0
(-475 3200);
DISPLAY 0.638298 (-475 3200);
DISPLAY INVISIBLE (-475 3200);
FORCEPROP 1 LAST MATERIAL CHIP
J 0
(0 3100);
DISPLAY 0.638298 (0 3100);
FORCEPROP 1 LAST TOLERANCE 1%
J 0
(-100 3100);
DISPLAY 0.638298 (-100 3100);
FORCEPROP 1 LAST VALUE 2K
J 2
(-125 3100);
DISPLAY 0.638298 (-125 3100);
FORCEPROP 1 LAST $LOCATION R1421
J 0
(-625 3100);
DISPLAY 0.787234 (-625 3100);
FORCEPROP 1 LASTPIN (-400 3100) $PN 1
J 0
(-388 3112);
DISPLAY 0.787234 (-388 3112);
FORCEPROP 1 LASTPIN (-200 3100) $PN 2
J 0
(-238 3112);
DISPLAY 0.787234 (-238 3112);
FORCEPROP 1 LAST WATTAGE 1/16W
J 2
(-100 3250);
DISPLAY 0.638298 (-100 3250);
DISPLAY INVISIBLE (-100 3250);
FORCEPROP 1 LAST PACK_TYPE 0402LF
J 0
(-475 3250);
DISPLAY 0.638298 (-475 3250);
DISPLAY INVISIBLE (-475 3250);
FORCEPROP 2 LAST CDS_LIB pure_quanta
J 0
(-300 3100);
PAINT MONO (-300 3100);
DISPLAY INVISIBLE (-300 3100);
FORCEPROP 1 LAST PATH I10
J 0
(-350 3250);
DISPLAY 0.978723 (-350 3250);
PAINT WHITE (-350 3250);
DISPLAY INVISIBLE (-350 3250);
FORCEPROP 2 LAST CDS_LOCATION R1421
J 0
(-350 3300);
DISPLAY 1.021277 (-350 3300);
DISPLAY INVISIBLE (-350 3300);
FORCEPROP 2 LAST $SEC 1
J 0
(-350 3300);
DISPLAY 0.680851 (-350 3300);
PAINT MONO (-350 3300);
DISPLAY INVISIBLE (-350 3300);
FORCEPROP 2 LAST CDS_SEC 1
J 0
(-350 3300);
DISPLAY 1.021277 (-350 3300);
DISPLAY INVISIBLE (-350 3300);
FORCEADD Q_RES..1
(-300 2525);
FORCEPROP 1 LAST PART_NUMBER CS22002FB07
J 0
(-475 2625);
DISPLAY 0.638298 (-475 2625);
DISPLAY INVISIBLE (-475 2625);
FORCEPROP 1 LAST TOLERANCE 1%
J 0
(-100 2525);
DISPLAY 0.638298 (-100 2525);
FORCEPROP 1 LAST MATERIAL EMPTY
J 0
(0 2525);
DISPLAY 0.638298 (0 2525);
PAINT RED (0 2525);
FORCEPROP 1 LAST VALUE 2K
J 2
(-125 2525);
DISPLAY 0.638298 (-125 2525);
FORCEPROP 1 LAST $LOCATION R1326
J 0
(-625 2525);
DISPLAY 0.808511 (-625 2525);
FORCEPROP 1 LASTPIN (-400 2525) $PN 1
J 0
(-388 2537);
DISPLAY 0.787234 (-388 2537);
FORCEPROP 1 LASTPIN (-200 2525) $PN 2
J 0
(-238 2537);
DISPLAY 0.787234 (-238 2537);
FORCEPROP 2 LAST CDS_LIB pure_quanta
J 0
(-300 2525);
PAINT MONO (-300 2525);
DISPLAY INVISIBLE (-300 2525);
FORCEPROP 1 LAST WATTAGE 1/16W
J 2
(-100 2675);
DISPLAY 0.638298 (-100 2675);
DISPLAY INVISIBLE (-100 2675);
FORCEPROP 1 LAST PACK_TYPE 0402LF
J 0
(-475 2675);
DISPLAY 0.638298 (-475 2675);
DISPLAY INVISIBLE (-475 2675);
FORCEPROP 1 LAST PATH I11
J 0
(-350 2675);
DISPLAY 0.978723 (-350 2675);
PAINT WHITE (-350 2675);
DISPLAY INVISIBLE (-350 2675);
FORCEPROP 2 LAST CDS_LOCATION R1326
J 0
(-350 2725);
DISPLAY 1.021277 (-350 2725);
DISPLAY INVISIBLE (-350 2725);
FORCEPROP 2 LAST $SEC 1
J 0
(-350 2725);
DISPLAY 0.680851 (-350 2725);
PAINT MONO (-350 2725);
DISPLAY INVISIBLE (-350 2725);
FORCEPROP 2 LAST CDS_SEC 1
J 0
(-350 2725);
DISPLAY 1.021277 (-350 2725);
DISPLAY INVISIBLE (-350 2725);
FORCEADD Q_RES..1
(-300 2675);
FORCEPROP 1 LAST PART_NUMBER CS22002FB07
J 0
(-475 2775);
DISPLAY 0.638298 (-475 2775);
DISPLAY INVISIBLE (-475 2775);
FORCEPROP 1 LAST TOLERANCE 1%
J 0
(-100 2675);
DISPLAY 0.638298 (-100 2675);
FORCEPROP 1 LAST MATERIAL EMPTY
J 0
(0 2675);
DISPLAY 0.638298 (0 2675);
PAINT RED (0 2675);
FORCEPROP 1 LAST VALUE 2K
J 2
(-125 2675);
DISPLAY 0.638298 (-125 2675);
FORCEPROP 1 LAST $LOCATION R1302
J 0
(-625 2675);
DISPLAY 0.808511 (-625 2675);
FORCEPROP 1 LASTPIN (-400 2675) $PN 1
J 0
(-388 2687);
DISPLAY 0.787234 (-388 2687);
FORCEPROP 1 LASTPIN (-200 2675) $PN 2
J 0
(-238 2687);
DISPLAY 0.787234 (-238 2687);
FORCEPROP 1 LAST PACK_TYPE 0402LF
J 0
(-475 2825);
DISPLAY 0.638298 (-475 2825);
DISPLAY INVISIBLE (-475 2825);
FORCEPROP 1 LAST WATTAGE 1/16W
J 2
(-100 2825);
DISPLAY 0.638298 (-100 2825);
DISPLAY INVISIBLE (-100 2825);
FORCEPROP 2 LAST CDS_LIB pure_quanta
J 0
(-300 2675);
PAINT MONO (-300 2675);
DISPLAY INVISIBLE (-300 2675);
FORCEPROP 1 LAST PATH I12
J 0
(-350 2825);
DISPLAY 0.978723 (-350 2825);
PAINT WHITE (-350 2825);
DISPLAY INVISIBLE (-350 2825);
FORCEPROP 2 LAST CDS_LOCATION R1302
J 0
(-350 2875);
DISPLAY 1.021277 (-350 2875);
DISPLAY INVISIBLE (-350 2875);
FORCEPROP 2 LAST $SEC 1
J 0
(-350 2875);
DISPLAY 0.680851 (-350 2875);
PAINT MONO (-350 2875);
DISPLAY INVISIBLE (-350 2875);
FORCEPROP 2 LAST CDS_SEC 1
J 0
(-350 2875);
DISPLAY 1.021277 (-350 2875);
DISPLAY INVISIBLE (-350 2875);
FORCEADD Q_RES..1
(-300 2225);
FORCEPROP 1 LAST PART_NUMBER CS22002FB07
J 0
(-475 2325);
DISPLAY 0.638298 (-475 2325);
DISPLAY INVISIBLE (-475 2325);
FORCEPROP 1 LAST VALUE 2K
J 2
(-125 2225);
DISPLAY 0.638298 (-125 2225);
FORCEPROP 1 LAST TOLERANCE 1%
J 0
(-100 2225);
DISPLAY 0.638298 (-100 2225);
FORCEPROP 1 LAST MATERIAL EMPTY
J 0
(0 2225);
DISPLAY 0.638298 (0 2225);
PAINT RED (0 2225);
FORCEPROP 1 LAST $LOCATION R1328
J 0
(-625 2225);
DISPLAY 0.808511 (-625 2225);
FORCEPROP 1 LASTPIN (-400 2225) $PN 1
J 0
(-388 2237);
DISPLAY 0.787234 (-388 2237);
FORCEPROP 1 LASTPIN (-200 2225) $PN 2
J 0
(-238 2237);
DISPLAY 0.787234 (-238 2237);
FORCEPROP 2 LAST CDS_LIB pure_quanta
J 0
(-300 2225);
PAINT MONO (-300 2225);
DISPLAY INVISIBLE (-300 2225);
FORCEPROP 1 LAST WATTAGE 1/16W
J 2
(-100 2375);
DISPLAY 0.638298 (-100 2375);
DISPLAY INVISIBLE (-100 2375);
FORCEPROP 1 LAST PACK_TYPE 0402LF
J 0
(-475 2375);
DISPLAY 0.638298 (-475 2375);
DISPLAY INVISIBLE (-475 2375);
FORCEPROP 1 LAST PATH I13
J 0
(-350 2375);
DISPLAY 0.978723 (-350 2375);
PAINT WHITE (-350 2375);
DISPLAY INVISIBLE (-350 2375);
FORCEPROP 2 LAST CDS_LOCATION R1328
J 0
(-350 2425);
DISPLAY 1.021277 (-350 2425);
DISPLAY INVISIBLE (-350 2425);
FORCEPROP 2 LAST $SEC 1
J 0
(-350 2425);
DISPLAY 0.680851 (-350 2425);
PAINT MONO (-350 2425);
DISPLAY INVISIBLE (-350 2425);
FORCEPROP 2 LAST CDS_SEC 1
J 0
(-350 2425);
DISPLAY 1.021277 (-350 2425);
DISPLAY INVISIBLE (-350 2425);
FORCEADD Q_RES..1
(-300 2375);
FORCEPROP 1 LAST PART_NUMBER CS22002FB07
J 0
(-475 2475);
DISPLAY 0.638298 (-475 2475);
DISPLAY INVISIBLE (-475 2475);
FORCEPROP 1 LAST TOLERANCE 1%
J 0
(-100 2375);
DISPLAY 0.638298 (-100 2375);
FORCEPROP 1 LAST VALUE 2K
J 2
(-125 2375);
DISPLAY 0.638298 (-125 2375);
FORCEPROP 1 LAST MATERIAL EMPTY
J 0
(0 2375);
DISPLAY 0.638298 (0 2375);
PAINT RED (0 2375);
FORCEPROP 1 LAST $LOCATION R1327
J 0
(-625 2375);
DISPLAY 0.808511 (-625 2375);
FORCEPROP 1 LASTPIN (-400 2375) $PN 1
J 0
(-388 2387);
DISPLAY 0.787234 (-388 2387);
FORCEPROP 1 LASTPIN (-200 2375) $PN 2
J 0
(-235 2385);
DISPLAY 0.787234 (-235 2385);
FORCEPROP 1 LAST PACK_TYPE 0402LF
J 0
(-475 2525);
DISPLAY 0.638298 (-475 2525);
DISPLAY INVISIBLE (-475 2525);
FORCEPROP 1 LAST WATTAGE 1/16W
J 2
(-100 2525);
DISPLAY 0.638298 (-100 2525);
DISPLAY INVISIBLE (-100 2525);
FORCEPROP 2 LAST CDS_LIB pure_quanta
J 0
(-300 2375);
PAINT MONO (-300 2375);
DISPLAY INVISIBLE (-300 2375);
FORCEPROP 1 LAST PATH I14
J 0
(-350 2525);
DISPLAY 0.978723 (-350 2525);
PAINT WHITE (-350 2525);
DISPLAY INVISIBLE (-350 2525);
FORCEPROP 2 LAST CDS_LOCATION R1327
J 0
(-350 2575);
DISPLAY 1.021277 (-350 2575);
DISPLAY INVISIBLE (-350 2575);
FORCEPROP 2 LAST $SEC 1
J 0
(-350 2575);
DISPLAY 0.680851 (-350 2575);
PAINT MONO (-350 2575);
DISPLAY INVISIBLE (-350 2575);
FORCEPROP 2 LAST CDS_SEC 1
J 0
(-350 2575);
DISPLAY 1.021277 (-350 2575);
DISPLAY INVISIBLE (-350 2575);
FORCEADD Q_RES..1
(-300 2075);
FORCEPROP 1 LAST PART_NUMBER CS22002FB07
J 0
(-475 2175);
DISPLAY 0.638298 (-475 2175);
DISPLAY INVISIBLE (-475 2175);
FORCEPROP 1 LAST VALUE 2K
J 2
(-125 2075);
DISPLAY 0.638298 (-125 2075);
FORCEPROP 1 LAST TOLERANCE 1%
J 0
(-100 2075);
DISPLAY 0.638298 (-100 2075);
FORCEPROP 1 LAST MATERIAL EMPTY
J 0
(0 2075);
DISPLAY 0.638298 (0 2075);
PAINT RED (0 2075);
FORCEPROP 1 LAST $LOCATION R1329
J 0
(-625 2075);
DISPLAY 0.808511 (-625 2075);
FORCEPROP 1 LASTPIN (-400 2075) $PN 1
J 0
(-388 2087);
DISPLAY 0.787234 (-388 2087);
FORCEPROP 1 LASTPIN (-200 2075) $PN 2
J 0
(-238 2087);
DISPLAY 0.787234 (-238 2087);
FORCEPROP 2 LAST CDS_LIB pure_quanta
J 0
(-300 2075);
PAINT MONO (-300 2075);
DISPLAY INVISIBLE (-300 2075);
FORCEPROP 1 LAST WATTAGE 1/16W
J 2
(-100 2225);
DISPLAY 0.638298 (-100 2225);
DISPLAY INVISIBLE (-100 2225);
FORCEPROP 1 LAST PACK_TYPE 0402LF
J 0
(-475 2225);
DISPLAY 0.638298 (-475 2225);
DISPLAY INVISIBLE (-475 2225);
FORCEPROP 1 LAST PATH I15
J 0
(-350 2225);
DISPLAY 0.978723 (-350 2225);
PAINT WHITE (-350 2225);
DISPLAY INVISIBLE (-350 2225);
FORCEPROP 2 LAST CDS_LOCATION R1329
J 0
(-350 2275);
DISPLAY 1.021277 (-350 2275);
DISPLAY INVISIBLE (-350 2275);
FORCEPROP 2 LAST $SEC 1
J 0
(-350 2275);
DISPLAY 0.680851 (-350 2275);
PAINT MONO (-350 2275);
DISPLAY INVISIBLE (-350 2275);
FORCEPROP 2 LAST CDS_SEC 1
J 0
(-350 2275);
DISPLAY 1.021277 (-350 2275);
DISPLAY INVISIBLE (-350 2275);
FORCEADD Q_RES..1
(-300 1925);
FORCEPROP 1 LAST PART_NUMBER CS22002FB07
J 0
(-475 2025);
DISPLAY 0.638298 (-475 2025);
DISPLAY INVISIBLE (-475 2025);
FORCEPROP 1 LAST VALUE 2K
J 2
(-125 1925);
DISPLAY 0.638298 (-125 1925);
FORCEPROP 1 LAST TOLERANCE 1%
J 0
(-100 1925);
DISPLAY 0.638298 (-100 1925);
FORCEPROP 1 LAST MATERIAL EMPTY
J 0
(0 1925);
DISPLAY 0.638298 (0 1925);
PAINT RED (0 1925);
FORCEPROP 1 LAST $LOCATION R1330
J 0
(-625 1925);
DISPLAY 0.808511 (-625 1925);
FORCEPROP 1 LASTPIN (-400 1925) $PN 1
J 0
(-388 1937);
DISPLAY 0.787234 (-388 1937);
FORCEPROP 1 LASTPIN (-200 1925) $PN 2
J 0
(-238 1937);
DISPLAY 0.787234 (-238 1937);
FORCEPROP 2 LAST CDS_LIB pure_quanta
J 0
(-300 1925);
PAINT MONO (-300 1925);
DISPLAY INVISIBLE (-300 1925);
FORCEPROP 1 LAST WATTAGE 1/16W
J 2
(-100 2075);
DISPLAY 0.638298 (-100 2075);
DISPLAY INVISIBLE (-100 2075);
FORCEPROP 1 LAST PACK_TYPE 0402LF
J 0
(-475 2075);
DISPLAY 0.638298 (-475 2075);
DISPLAY INVISIBLE (-475 2075);
FORCEPROP 1 LAST PATH I16
J 0
(-350 2075);
DISPLAY 0.978723 (-350 2075);
PAINT WHITE (-350 2075);
DISPLAY INVISIBLE (-350 2075);
FORCEPROP 2 LAST CDS_LOCATION R1330
J 0
(-350 2125);
DISPLAY 1.021277 (-350 2125);
DISPLAY INVISIBLE (-350 2125);
FORCEPROP 2 LAST $SEC 1
J 0
(-350 2125);
DISPLAY 0.680851 (-350 2125);
PAINT MONO (-350 2125);
DISPLAY INVISIBLE (-350 2125);
FORCEPROP 2 LAST CDS_SEC 1
J 0
(-350 2125);
DISPLAY 1.021277 (-350 2125);
DISPLAY INVISIBLE (-350 2125);
FORCEADD Q_RES..1
(-300 1775);
FORCEPROP 1 LAST PART_NUMBER CS22002FB07
J 0
(-475 1875);
DISPLAY 0.638298 (-475 1875);
DISPLAY INVISIBLE (-475 1875);
FORCEPROP 1 LAST VALUE 2K
J 2
(-125 1775);
DISPLAY 0.638298 (-125 1775);
FORCEPROP 1 LAST MATERIAL EMPTY
J 0
(0 1775);
DISPLAY 0.638298 (0 1775);
PAINT RED (0 1775);
FORCEPROP 1 LAST TOLERANCE 1%
J 0
(-100 1775);
DISPLAY 0.638298 (-100 1775);
FORCEPROP 1 LAST $LOCATION R1388
J 0
(-625 1775);
DISPLAY 0.808511 (-625 1775);
FORCEPROP 1 LASTPIN (-400 1775) $PN 1
J 0
(-388 1787);
DISPLAY 0.787234 (-388 1787);
FORCEPROP 1 LASTPIN (-200 1775) $PN 2
J 0
(-238 1787);
DISPLAY 0.787234 (-238 1787);
FORCEPROP 2 LAST CDS_LIB pure_quanta
J 0
(-300 1775);
PAINT MONO (-300 1775);
DISPLAY INVISIBLE (-300 1775);
FORCEPROP 1 LAST WATTAGE 1/16W
J 2
(-100 1925);
DISPLAY 0.638298 (-100 1925);
DISPLAY INVISIBLE (-100 1925);
FORCEPROP 1 LAST PACK_TYPE 0402LF
J 0
(-475 1925);
DISPLAY 0.638298 (-475 1925);
DISPLAY INVISIBLE (-475 1925);
FORCEPROP 1 LAST PATH I17
J 0
(-350 1925);
DISPLAY 0.978723 (-350 1925);
PAINT WHITE (-350 1925);
DISPLAY INVISIBLE (-350 1925);
FORCEPROP 2 LAST CDS_LOCATION R1388
J 0
(-350 1975);
DISPLAY 1.021277 (-350 1975);
DISPLAY INVISIBLE (-350 1975);
FORCEPROP 2 LAST $SEC 1
J 0
(-350 1975);
DISPLAY 0.680851 (-350 1975);
PAINT MONO (-350 1975);
DISPLAY INVISIBLE (-350 1975);
FORCEPROP 2 LAST CDS_SEC 1
J 0
(-350 1975);
DISPLAY 1.021277 (-350 1975);
DISPLAY INVISIBLE (-350 1975);
FORCEADD Q_RES..1
(-300 1250);
FORCEPROP 1 LAST PART_NUMBER CS22002FB07
J 0
(-475 1350);
DISPLAY 0.638298 (-475 1350);
DISPLAY INVISIBLE (-475 1350);
FORCEPROP 1 LAST MATERIAL CHIP
J 0
(0 1250);
DISPLAY 0.638298 (0 1250);
FORCEPROP 1 LAST TOLERANCE 1%
J 0
(-100 1250);
DISPLAY 0.638298 (-100 1250);
FORCEPROP 1 LAST PACK_TYPE 0402LF
J 0
(-475 1400);
DISPLAY 0.638298 (-475 1400);
FORCEPROP 1 LAST VALUE 2K
J 2
(-125 1250);
DISPLAY 0.638298 (-125 1250);
FORCEPROP 1 LAST WATTAGE 1/16W
J 2
(-100 1400);
DISPLAY 0.638298 (-100 1400);
FORCEPROP 1 LAST $LOCATION R990
J 0
(-625 1250);
DISPLAY 0.787234 (-625 1250);
FORCEPROP 1 LASTPIN (-400 1250) $PN 1
J 0
(-388 1262);
DISPLAY 0.787234 (-388 1262);
FORCEPROP 1 LASTPIN (-200 1250) $PN 2
J 0
(-238 1262);
DISPLAY 0.787234 (-238 1262);
FORCEPROP 2 LAST CDS_LIB pure_quanta
J 0
(-300 1250);
PAINT MONO (-300 1250);
DISPLAY INVISIBLE (-300 1250);
FORCEPROP 1 LAST PATH I18
J 0
(-350 1400);
DISPLAY 0.978723 (-350 1400);
PAINT WHITE (-350 1400);
DISPLAY INVISIBLE (-350 1400);
FORCEPROP 2 LAST CDS_LOCATION R990
J 0
(-100 1450);
DISPLAY 1.021277 (-100 1450);
DISPLAY INVISIBLE (-100 1450);
FORCEPROP 2 LAST $SEC 1
J 0
(-100 1450);
DISPLAY 0.680851 (-100 1450);
PAINT MONO (-100 1450);
DISPLAY INVISIBLE (-100 1450);
FORCEPROP 2 LAST CDS_SEC 1
J 0
(-100 1450);
DISPLAY 1.021277 (-100 1450);
DISPLAY INVISIBLE (-100 1450);
FORCEADD Q_RES..1
(-300 1625);
FORCEPROP 1 LAST PART_NUMBER CS22002FB07
J 0
(-475 1725);
DISPLAY 0.638298 (-475 1725);
DISPLAY INVISIBLE (-475 1725);
FORCEPROP 1 LAST VALUE 2K
J 2
(-125 1625);
DISPLAY 0.638298 (-125 1625);
FORCEPROP 1 LAST TOLERANCE 1%
J 0
(-100 1625);
DISPLAY 0.638298 (-100 1625);
FORCEPROP 1 LAST MATERIAL EMPTY
J 0
(0 1625);
DISPLAY 0.638298 (0 1625);
PAINT RED (0 1625);
FORCEPROP 1 LAST $LOCATION R4533
J 0
(-625 1625);
DISPLAY 0.808511 (-625 1625);
FORCEPROP 1 LASTPIN (-400 1625) $PN 1
J 0
(-388 1637);
DISPLAY 0.787234 (-388 1637);
FORCEPROP 1 LASTPIN (-200 1625) $PN 2
J 0
(-238 1637);
DISPLAY 0.787234 (-238 1637);
FORCEPROP 2 LAST CDS_LIB pure_quanta
J 0
(-300 1625);
PAINT MONO (-300 1625);
DISPLAY INVISIBLE (-300 1625);
FORCEPROP 1 LAST WATTAGE 1/16W
J 2
(-100 1775);
DISPLAY 0.638298 (-100 1775);
DISPLAY INVISIBLE (-100 1775);
FORCEPROP 1 LAST PACK_TYPE 0402LF
J 0
(-475 1775);
DISPLAY 0.638298 (-475 1775);
DISPLAY INVISIBLE (-475 1775);
FORCEPROP 1 LAST PATH I19
J 0
(-350 1775);
DISPLAY 0.978723 (-350 1775);
PAINT WHITE (-350 1775);
DISPLAY INVISIBLE (-350 1775);
FORCEPROP 2 LAST CDS_LOCATION R4533
J 0
(-350 1825);
DISPLAY 1.021277 (-350 1825);
DISPLAY INVISIBLE (-350 1825);
FORCEPROP 2 LAST $SEC 1
J 0
(-350 1825);
DISPLAY 0.680851 (-350 1825);
PAINT MONO (-350 1825);
DISPLAY INVISIBLE (-350 1825);
FORCEPROP 2 LAST CDS_SEC 1
J 0
(-350 1825);
DISPLAY 1.021277 (-350 1825);
DISPLAY INVISIBLE (-350 1825);
FORCEADD OFFPAGE..1
(-2200 -850);
FORCEPROP 2 LAST $XR1 222 
J 0
(-2572 -850);
DISPLAY 0.638298 (-2572 -850);
PAINT MONO (-2572 -850);
FORCEPROP 2 LAST $XR0 214 
J 0
(-2452 -850);
DISPLAY 0.638298 (-2452 -850);
PAINT MONO (-2452 -850);
FORCEPROP 2 LAST CDS_LIB standard
J 0
(-2200 -850);
PAINT MONO (-2200 -850);
DISPLAY INVISIBLE (-2200 -850);
FORCEPROP 1 LAST OFFPAGE TRUE
J 0
(-1875 -975);
DISPLAY 0.872340 (-1875 -975);
PAINT GREEN (-1875 -975);
DISPLAY INVISIBLE (-1875 -975);
FORCEPROP 1 LAST COMMENT_BODY TRUE
J 0
(-2075 -950);
DISPLAY 0.872340 (-2075 -950);
PAINT GREEN (-2075 -950);
DISPLAY INVISIBLE (-2075 -950);
FORCEPROP 2 LAST PATH I2
J 0
(-2500 -800);
DISPLAY 1.021277 (-2500 -800);
DISPLAY INVISIBLE (-2500 -800);
FORCEADD Q_RES..1
(-300 1100);
FORCEPROP 1 LAST PART_NUMBER CS22002FB07
J 0
(-475 1200);
DISPLAY 0.638298 (-475 1200);
DISPLAY INVISIBLE (-475 1200);
FORCEPROP 1 LAST MATERIAL CHIP
J 0
(0 1100);
DISPLAY 0.638298 (0 1100);
FORCEPROP 1 LAST TOLERANCE 1%
J 0
(-100 1100);
DISPLAY 0.638298 (-100 1100);
FORCEPROP 1 LAST VALUE 2K
J 2
(-125 1100);
DISPLAY 0.638298 (-125 1100);
FORCEPROP 1 LAST $LOCATION R991
J 0
(-625 1100);
DISPLAY 0.787234 (-625 1100);
FORCEPROP 1 LASTPIN (-400 1100) $PN 1
J 0
(-388 1112);
DISPLAY 0.787234 (-388 1112);
FORCEPROP 1 LASTPIN (-200 1100) $PN 2
J 0
(-238 1112);
DISPLAY 0.787234 (-238 1112);
FORCEPROP 2 LAST CDS_LIB pure_quanta
J 0
(-300 1100);
PAINT MONO (-300 1100);
DISPLAY INVISIBLE (-300 1100);
FORCEPROP 1 LAST PACK_TYPE 0402LF
J 0
(-475 1250);
DISPLAY 0.638298 (-475 1250);
DISPLAY INVISIBLE (-475 1250);
FORCEPROP 1 LAST WATTAGE 1/16W
J 2
(-100 1250);
DISPLAY 0.638298 (-100 1250);
DISPLAY INVISIBLE (-100 1250);
FORCEPROP 1 LAST PATH I20
J 0
(-350 1250);
DISPLAY 0.978723 (-350 1250);
PAINT WHITE (-350 1250);
DISPLAY INVISIBLE (-350 1250);
FORCEPROP 2 LAST CDS_LOCATION R991
J 0
(-350 1300);
DISPLAY 1.021277 (-350 1300);
DISPLAY INVISIBLE (-350 1300);
FORCEPROP 2 LAST $SEC 1
J 0
(-350 1300);
DISPLAY 0.680851 (-350 1300);
PAINT MONO (-350 1300);
DISPLAY INVISIBLE (-350 1300);
FORCEPROP 2 LAST CDS_SEC 1
J 0
(-350 1300);
DISPLAY 1.021277 (-350 1300);
DISPLAY INVISIBLE (-350 1300);
FORCEADD Q_RES..1
(-300 950);
FORCEPROP 1 LAST PART_NUMBER CS22002FB07
J 0
(-475 1050);
DISPLAY 0.638298 (-475 1050);
DISPLAY INVISIBLE (-475 1050);
FORCEPROP 1 LAST TOLERANCE 1%
J 0
(-100 950);
DISPLAY 0.638298 (-100 950);
FORCEPROP 1 LAST VALUE 2K
J 2
(-125 950);
DISPLAY 0.638298 (-125 950);
FORCEPROP 1 LAST MATERIAL EMPTY
J 0
(0 950);
DISPLAY 0.638298 (0 950);
PAINT RED (0 950);
FORCEPROP 1 LAST $LOCATION R992
J 0
(-625 950);
DISPLAY 0.787234 (-625 950);
FORCEPROP 1 LASTPIN (-400 950) $PN 1
J 0
(-388 962);
DISPLAY 0.787234 (-388 962);
FORCEPROP 1 LASTPIN (-200 950) $PN 2
J 0
(-238 962);
DISPLAY 0.787234 (-238 962);
FORCEPROP 2 LAST CDS_LIB pure_quanta
J 0
(-300 950);
PAINT MONO (-300 950);
DISPLAY INVISIBLE (-300 950);
FORCEPROP 1 LAST PACK_TYPE 0402LF
J 0
(-475 1100);
DISPLAY 0.638298 (-475 1100);
DISPLAY INVISIBLE (-475 1100);
FORCEPROP 1 LAST WATTAGE 1/16W
J 2
(-100 1100);
DISPLAY 0.638298 (-100 1100);
DISPLAY INVISIBLE (-100 1100);
FORCEPROP 1 LAST PATH I21
J 0
(-350 1100);
DISPLAY 0.978723 (-350 1100);
PAINT WHITE (-350 1100);
DISPLAY INVISIBLE (-350 1100);
FORCEPROP 2 LAST CDS_LOCATION R992
J 0
(-350 1150);
DISPLAY 1.021277 (-350 1150);
DISPLAY INVISIBLE (-350 1150);
FORCEPROP 2 LAST $SEC 1
J 0
(-350 1150);
DISPLAY 0.680851 (-350 1150);
PAINT MONO (-350 1150);
DISPLAY INVISIBLE (-350 1150);
FORCEPROP 2 LAST CDS_SEC 1
J 0
(-350 1150);
DISPLAY 1.021277 (-350 1150);
DISPLAY INVISIBLE (-350 1150);
FORCEADD Q_RES..1
(-300 800);
FORCEPROP 1 LAST PART_NUMBER CS22002FB07
J 0
(-475 900);
DISPLAY 0.638298 (-475 900);
DISPLAY INVISIBLE (-475 900);
FORCEPROP 1 LAST TOLERANCE 1%
J 0
(-100 800);
DISPLAY 0.638298 (-100 800);
FORCEPROP 1 LAST VALUE 2K
J 2
(-125 800);
DISPLAY 0.638298 (-125 800);
FORCEPROP 1 LAST MATERIAL EMPTY
J 0
(0 800);
DISPLAY 0.638298 (0 800);
PAINT RED (0 800);
FORCEPROP 1 LAST $LOCATION R1398
J 0
(-625 800);
DISPLAY 0.787234 (-625 800);
FORCEPROP 1 LASTPIN (-400 800) $PN 1
J 0
(-388 812);
DISPLAY 0.787234 (-388 812);
FORCEPROP 1 LASTPIN (-200 800) $PN 2
J 0
(-238 812);
DISPLAY 0.787234 (-238 812);
FORCEPROP 2 LAST CDS_LIB pure_quanta
J 0
(-300 800);
PAINT MONO (-300 800);
DISPLAY INVISIBLE (-300 800);
FORCEPROP 1 LAST PACK_TYPE 0402LF
J 0
(-475 950);
DISPLAY 0.638298 (-475 950);
DISPLAY INVISIBLE (-475 950);
FORCEPROP 1 LAST WATTAGE 1/16W
J 2
(-100 950);
DISPLAY 0.638298 (-100 950);
DISPLAY INVISIBLE (-100 950);
FORCEPROP 1 LAST PATH I22
J 0
(-350 950);
DISPLAY 0.978723 (-350 950);
PAINT WHITE (-350 950);
DISPLAY INVISIBLE (-350 950);
FORCEPROP 2 LAST CDS_LOCATION R1398
J 0
(-350 1000);
DISPLAY 1.021277 (-350 1000);
DISPLAY INVISIBLE (-350 1000);
FORCEPROP 2 LAST $SEC 1
J 0
(-350 1000);
DISPLAY 0.680851 (-350 1000);
PAINT MONO (-350 1000);
DISPLAY INVISIBLE (-350 1000);
FORCEPROP 2 LAST CDS_SEC 1
J 0
(-350 1000);
DISPLAY 1.021277 (-350 1000);
DISPLAY INVISIBLE (-350 1000);
FORCEADD Q_RES..1
(-300 650);
FORCEPROP 1 LAST PART_NUMBER CS22002FB07
J 0
(-475 750);
DISPLAY 0.638298 (-475 750);
DISPLAY INVISIBLE (-475 750);
FORCEPROP 1 LAST VALUE 2K
J 2
(-125 650);
DISPLAY 0.638298 (-125 650);
FORCEPROP 1 LAST MATERIAL CHIP
J 0
(0 650);
DISPLAY 0.638298 (0 650);
FORCEPROP 1 LAST $LOCATION R1402
J 0
(-625 650);
DISPLAY 0.787234 (-625 650);
FORCEPROP 1 LASTPIN (-400 650) $PN 1
J 0
(-388 662);
DISPLAY 0.787234 (-388 662);
FORCEPROP 1 LASTPIN (-200 650) $PN 2
J 0
(-238 662);
DISPLAY 0.787234 (-238 662);
FORCEPROP 1 LAST TOLERANCE 1%
J 0
(-100 650);
DISPLAY 0.638298 (-100 650);
FORCEPROP 2 LAST CDS_LIB pure_quanta
J 0
(-300 650);
PAINT MONO (-300 650);
DISPLAY INVISIBLE (-300 650);
FORCEPROP 1 LAST PACK_TYPE 0402LF
J 0
(-475 800);
DISPLAY 0.638298 (-475 800);
DISPLAY INVISIBLE (-475 800);
FORCEPROP 1 LAST WATTAGE 1/16W
J 2
(-100 800);
DISPLAY 0.638298 (-100 800);
DISPLAY INVISIBLE (-100 800);
FORCEPROP 1 LAST PATH I23
J 0
(-350 800);
DISPLAY 0.978723 (-350 800);
PAINT WHITE (-350 800);
DISPLAY INVISIBLE (-350 800);
FORCEPROP 2 LAST CDS_LOCATION R1402
J 0
(-350 850);
DISPLAY 1.021277 (-350 850);
DISPLAY INVISIBLE (-350 850);
FORCEPROP 2 LAST $SEC 1
J 0
(-350 850);
DISPLAY 0.680851 (-350 850);
PAINT MONO (-350 850);
DISPLAY INVISIBLE (-350 850);
FORCEPROP 2 LAST CDS_SEC 1
J 0
(-350 850);
DISPLAY 1.021277 (-350 850);
DISPLAY INVISIBLE (-350 850);
FORCEADD Q_RES..1
(-300 500);
FORCEPROP 1 LAST PART_NUMBER CS22002FB07
J 0
(-475 600);
DISPLAY 0.638298 (-475 600);
DISPLAY INVISIBLE (-475 600);
FORCEPROP 1 LAST MATERIAL CHIP
J 0
(0 500);
DISPLAY 0.638298 (0 500);
FORCEPROP 1 LAST VALUE 2K
J 2
(-125 500);
DISPLAY 0.638298 (-125 500);
FORCEPROP 1 LAST TOLERANCE 1%
J 0
(-100 500);
DISPLAY 0.638298 (-100 500);
FORCEPROP 1 LAST $LOCATION R1403
J 0
(-625 500);
DISPLAY 0.787234 (-625 500);
FORCEPROP 1 LASTPIN (-400 500) $PN 1
J 0
(-388 512);
DISPLAY 0.787234 (-388 512);
FORCEPROP 1 LASTPIN (-200 500) $PN 2
J 0
(-238 512);
DISPLAY 0.787234 (-238 512);
FORCEPROP 1 LAST WATTAGE 1/16W
J 2
(-100 650);
DISPLAY 0.638298 (-100 650);
DISPLAY INVISIBLE (-100 650);
FORCEPROP 1 LAST PACK_TYPE 0402LF
J 0
(-475 650);
DISPLAY 0.638298 (-475 650);
DISPLAY INVISIBLE (-475 650);
FORCEPROP 2 LAST CDS_LIB pure_quanta
J 0
(-300 500);
PAINT MONO (-300 500);
DISPLAY INVISIBLE (-300 500);
FORCEPROP 1 LAST PATH I24
J 0
(-350 650);
DISPLAY 0.978723 (-350 650);
PAINT WHITE (-350 650);
DISPLAY INVISIBLE (-350 650);
FORCEPROP 2 LAST CDS_LOCATION R1403
J 0
(-350 700);
DISPLAY 1.021277 (-350 700);
DISPLAY INVISIBLE (-350 700);
FORCEPROP 2 LAST $SEC 1
J 0
(-350 700);
DISPLAY 0.680851 (-350 700);
PAINT MONO (-350 700);
DISPLAY INVISIBLE (-350 700);
FORCEPROP 2 LAST CDS_SEC 1
J 0
(-350 700);
DISPLAY 1.021277 (-350 700);
DISPLAY INVISIBLE (-350 700);
FORCEADD Q_RES..1
(-300 350);
FORCEPROP 1 LAST PART_NUMBER CS22002FB07
J 0
(-475 450);
DISPLAY 0.638298 (-475 450);
DISPLAY INVISIBLE (-475 450);
FORCEPROP 1 LAST MATERIAL CHIP
J 0
(0 350);
DISPLAY 0.638298 (0 350);
FORCEPROP 1 LAST VALUE 2K
J 2
(-125 350);
DISPLAY 0.638298 (-125 350);
FORCEPROP 1 LAST TOLERANCE 1%
J 0
(-100 350);
DISPLAY 0.638298 (-100 350);
FORCEPROP 1 LAST $LOCATION R1404
J 0
(-625 350);
DISPLAY 0.787234 (-625 350);
FORCEPROP 1 LASTPIN (-400 350) $PN 1
J 0
(-388 362);
DISPLAY 0.787234 (-388 362);
FORCEPROP 1 LASTPIN (-200 350) $PN 2
J 0
(-238 362);
DISPLAY 0.787234 (-238 362);
FORCEPROP 1 LAST WATTAGE 1/16W
J 2
(-100 500);
DISPLAY 0.638298 (-100 500);
DISPLAY INVISIBLE (-100 500);
FORCEPROP 1 LAST PACK_TYPE 0402LF
J 0
(-475 500);
DISPLAY 0.638298 (-475 500);
DISPLAY INVISIBLE (-475 500);
FORCEPROP 2 LAST CDS_LIB pure_quanta
J 0
(-300 350);
PAINT MONO (-300 350);
DISPLAY INVISIBLE (-300 350);
FORCEPROP 1 LAST PATH I25
J 0
(-350 500);
DISPLAY 0.978723 (-350 500);
PAINT WHITE (-350 500);
DISPLAY INVISIBLE (-350 500);
FORCEPROP 2 LAST CDS_LOCATION R1404
J 0
(-350 550);
DISPLAY 1.021277 (-350 550);
DISPLAY INVISIBLE (-350 550);
FORCEPROP 2 LAST $SEC 1
J 0
(-350 550);
DISPLAY 0.680851 (-350 550);
PAINT MONO (-350 550);
DISPLAY INVISIBLE (-350 550);
FORCEPROP 2 LAST CDS_SEC 1
J 0
(-350 550);
DISPLAY 1.021277 (-350 550);
DISPLAY INVISIBLE (-350 550);
FORCEADD Q_RES..1
(-300 200);
FORCEPROP 1 LAST PART_NUMBER CS22002FB07
J 0
(-475 300);
DISPLAY 0.638298 (-475 300);
DISPLAY INVISIBLE (-475 300);
FORCEPROP 1 LAST TOLERANCE 1%
J 0
(-100 200);
DISPLAY 0.638298 (-100 200);
FORCEPROP 1 LAST VALUE 2K
J 2
(-125 200);
DISPLAY 0.638298 (-125 200);
FORCEPROP 1 LAST MATERIAL CHIP
J 0
(0 200);
DISPLAY 0.638298 (0 200);
FORCEPROP 1 LAST $LOCATION R1405
J 0
(-625 200);
DISPLAY 0.787234 (-625 200);
FORCEPROP 1 LASTPIN (-400 200) $PN 1
J 0
(-388 212);
DISPLAY 0.787234 (-388 212);
FORCEPROP 1 LASTPIN (-200 200) $PN 2
J 0
(-238 212);
DISPLAY 0.787234 (-238 212);
FORCEPROP 2 LAST CDS_LIB pure_quanta
J 0
(-300 200);
PAINT MONO (-300 200);
DISPLAY INVISIBLE (-300 200);
FORCEPROP 1 LAST PACK_TYPE 0402LF
J 0
(-475 350);
DISPLAY 0.638298 (-475 350);
DISPLAY INVISIBLE (-475 350);
FORCEPROP 1 LAST WATTAGE 1/16W
J 2
(-100 350);
DISPLAY 0.638298 (-100 350);
DISPLAY INVISIBLE (-100 350);
FORCEPROP 1 LAST PATH I26
J 0
(-350 350);
DISPLAY 0.978723 (-350 350);
PAINT WHITE (-350 350);
DISPLAY INVISIBLE (-350 350);
FORCEPROP 2 LAST CDS_LOCATION R1405
J 0
(-350 400);
DISPLAY 1.021277 (-350 400);
DISPLAY INVISIBLE (-350 400);
FORCEPROP 2 LAST $SEC 1
J 0
(-350 400);
DISPLAY 0.680851 (-350 400);
PAINT MONO (-350 400);
DISPLAY INVISIBLE (-350 400);
FORCEPROP 2 LAST CDS_SEC 1
J 0
(-350 400);
DISPLAY 1.021277 (-350 400);
DISPLAY INVISIBLE (-350 400);
FORCEADD OFFPAGE..1
(-2200 4000);
FORCEPROP 2 LAST $XR1 124 
J 0
(-2572 4000);
DISPLAY 0.638298 (-2572 4000);
PAINT MONO (-2572 4000);
FORCEPROP 2 LAST $XR0 216 
J 0
(-2452 4000);
DISPLAY 0.638298 (-2452 4000);
PAINT MONO (-2452 4000);
FORCEPROP 2 LAST CDS_LIB standard
J 0
(-2200 4000);
PAINT MONO (-2200 4000);
DISPLAY INVISIBLE (-2200 4000);
FORCEPROP 1 LAST OFFPAGE TRUE
J 0
(-1875 3875);
DISPLAY 0.872340 (-1875 3875);
PAINT GREEN (-1875 3875);
DISPLAY INVISIBLE (-1875 3875);
FORCEPROP 1 LAST COMMENT_BODY TRUE
J 0
(-2075 3900);
DISPLAY 0.872340 (-2075 3900);
PAINT GREEN (-2075 3900);
DISPLAY INVISIBLE (-2075 3900);
FORCEPROP 2 LAST PATH I27
J 0
(-2500 4050);
DISPLAY 1.021277 (-2500 4050);
DISPLAY INVISIBLE (-2500 4050);
FORCEADD OFFPAGE..1
(-2200 3850);
FORCEPROP 2 LAST $XR1 125 
J 0
(-2572 3850);
DISPLAY 0.638298 (-2572 3850);
PAINT MONO (-2572 3850);
FORCEPROP 2 LAST $XR0 216 
J 0
(-2452 3850);
DISPLAY 0.638298 (-2452 3850);
PAINT MONO (-2452 3850);
FORCEPROP 2 LAST CDS_LIB standard
J 0
(-2200 3850);
PAINT MONO (-2200 3850);
DISPLAY INVISIBLE (-2200 3850);
FORCEPROP 1 LAST OFFPAGE TRUE
J 0
(-1875 3725);
DISPLAY 0.872340 (-1875 3725);
PAINT GREEN (-1875 3725);
DISPLAY INVISIBLE (-1875 3725);
FORCEPROP 1 LAST COMMENT_BODY TRUE
J 0
(-2075 3750);
DISPLAY 0.872340 (-2075 3750);
PAINT GREEN (-2075 3750);
DISPLAY INVISIBLE (-2075 3750);
FORCEPROP 2 LAST PATH I28
J 0
(-2500 3900);
DISPLAY 1.021277 (-2500 3900);
DISPLAY INVISIBLE (-2500 3900);
FORCEADD OFFPAGE..1
(-2200 3700);
FORCEPROP 2 LAST $XR1 223 
J 0
(-2572 3700);
DISPLAY 0.638298 (-2572 3700);
PAINT MONO (-2572 3700);
FORCEPROP 2 LAST $XR0 214 
J 0
(-2452 3700);
DISPLAY 0.638298 (-2452 3700);
PAINT MONO (-2452 3700);
FORCEPROP 2 LAST CDS_LIB standard
J 0
(-2200 3700);
PAINT MONO (-2200 3700);
DISPLAY INVISIBLE (-2200 3700);
FORCEPROP 1 LAST OFFPAGE TRUE
J 0
(-1875 3575);
DISPLAY 0.872340 (-1875 3575);
PAINT GREEN (-1875 3575);
DISPLAY INVISIBLE (-1875 3575);
FORCEPROP 1 LAST COMMENT_BODY TRUE
J 0
(-2075 3600);
DISPLAY 0.872340 (-2075 3600);
PAINT GREEN (-2075 3600);
DISPLAY INVISIBLE (-2075 3600);
FORCEPROP 2 LAST PATH I29
J 0
(-2500 3750);
DISPLAY 1.021277 (-2500 3750);
DISPLAY INVISIBLE (-2500 3750);
FORCEADD OFFPAGE..1
(-2200 -1000);
FORCEPROP 2 LAST $XR1 278 
J 0
(-2572 -1000);
DISPLAY 0.638298 (-2572 -1000);
PAINT MONO (-2572 -1000);
FORCEPROP 2 LAST $XR0 214 
J 0
(-2452 -1000);
DISPLAY 0.638298 (-2452 -1000);
PAINT MONO (-2452 -1000);
FORCEPROP 2 LAST CDS_LIB standard
J 0
(-2200 -1000);
PAINT MONO (-2200 -1000);
DISPLAY INVISIBLE (-2200 -1000);
FORCEPROP 1 LAST OFFPAGE TRUE
J 0
(-1875 -1125);
DISPLAY 0.872340 (-1875 -1125);
PAINT GREEN (-1875 -1125);
DISPLAY INVISIBLE (-1875 -1125);
FORCEPROP 1 LAST COMMENT_BODY TRUE
J 0
(-2075 -1100);
DISPLAY 0.872340 (-2075 -1100);
PAINT GREEN (-2075 -1100);
DISPLAY INVISIBLE (-2075 -1100);
FORCEPROP 2 LAST PATH I3
J 0
(-2500 -950);
DISPLAY 1.021277 (-2500 -950);
DISPLAY INVISIBLE (-2500 -950);
FORCEADD OFFPAGE..1
(-2200 3550);
FORCEPROP 2 LAST $XR1 223 
J 0
(-2572 3550);
DISPLAY 0.638298 (-2572 3550);
PAINT MONO (-2572 3550);
FORCEPROP 2 LAST $XR0 214 
J 0
(-2452 3550);
DISPLAY 0.638298 (-2452 3550);
PAINT MONO (-2452 3550);
FORCEPROP 2 LAST CDS_LIB standard
J 0
(-2200 3550);
PAINT MONO (-2200 3550);
DISPLAY INVISIBLE (-2200 3550);
FORCEPROP 1 LAST OFFPAGE TRUE
J 0
(-1875 3425);
DISPLAY 0.872340 (-1875 3425);
PAINT GREEN (-1875 3425);
DISPLAY INVISIBLE (-1875 3425);
FORCEPROP 1 LAST COMMENT_BODY TRUE
J 0
(-2075 3450);
DISPLAY 0.872340 (-2075 3450);
PAINT GREEN (-2075 3450);
DISPLAY INVISIBLE (-2075 3450);
FORCEPROP 2 LAST PATH I30
J 0
(-2500 3600);
DISPLAY 1.021277 (-2500 3600);
DISPLAY INVISIBLE (-2500 3600);
FORCEADD OFFPAGE..1
(-2200 3250);
FORCEPROP 2 LAST $XR1 223 
J 0
(-2572 3250);
DISPLAY 0.638298 (-2572 3250);
PAINT MONO (-2572 3250);
FORCEPROP 2 LAST $XR0 215 
J 0
(-2452 3250);
DISPLAY 0.638298 (-2452 3250);
PAINT MONO (-2452 3250);
FORCEPROP 2 LAST CDS_LIB standard
J 0
(-2200 3250);
PAINT MONO (-2200 3250);
DISPLAY INVISIBLE (-2200 3250);
FORCEPROP 1 LAST OFFPAGE TRUE
J 0
(-1875 3125);
DISPLAY 0.872340 (-1875 3125);
PAINT GREEN (-1875 3125);
DISPLAY INVISIBLE (-1875 3125);
FORCEPROP 1 LAST COMMENT_BODY TRUE
J 0
(-2075 3150);
DISPLAY 0.872340 (-2075 3150);
PAINT GREEN (-2075 3150);
DISPLAY INVISIBLE (-2075 3150);
FORCEPROP 2 LAST PATH I31
J 0
(-2500 3300);
DISPLAY 1.021277 (-2500 3300);
DISPLAY INVISIBLE (-2500 3300);
FORCEADD OFFPAGE..1
(-2200 3400);
FORCEPROP 2 LAST $XR0 215 
J 0
(-2452 3400);
DISPLAY 0.638298 (-2452 3400);
PAINT MONO (-2452 3400);
FORCEPROP 2 LAST CDS_LIB standard
J 0
(-2200 3400);
PAINT MONO (-2200 3400);
DISPLAY INVISIBLE (-2200 3400);
FORCEPROP 1 LAST OFFPAGE TRUE
J 0
(-1875 3275);
DISPLAY 0.872340 (-1875 3275);
PAINT GREEN (-1875 3275);
DISPLAY INVISIBLE (-1875 3275);
FORCEPROP 1 LAST COMMENT_BODY TRUE
J 0
(-2075 3300);
DISPLAY 0.872340 (-2075 3300);
PAINT GREEN (-2075 3300);
DISPLAY INVISIBLE (-2075 3300);
FORCEPROP 2 LAST PATH I32
J 0
(-2500 3450);
DISPLAY 1.021277 (-2500 3450);
DISPLAY INVISIBLE (-2500 3450);
FORCEADD OFFPAGE..1
(-2200 3100);
FORCEPROP 2 LAST $XR2 252 
J 0
(-2692 3100);
DISPLAY 0.638298 (-2692 3100);
PAINT MONO (-2692 3100);
FORCEPROP 2 LAST $XR1 223 
J 0
(-2572 3100);
DISPLAY 0.638298 (-2572 3100);
PAINT MONO (-2572 3100);
FORCEPROP 2 LAST $XR0 215 
J 0
(-2452 3100);
DISPLAY 0.638298 (-2452 3100);
PAINT MONO (-2452 3100);
FORCEPROP 2 LAST CDS_LIB standard
J 0
(-2200 3100);
PAINT MONO (-2200 3100);
DISPLAY INVISIBLE (-2200 3100);
FORCEPROP 1 LAST OFFPAGE TRUE
J 0
(-1875 2975);
DISPLAY 0.872340 (-1875 2975);
PAINT GREEN (-1875 2975);
DISPLAY INVISIBLE (-1875 2975);
FORCEPROP 1 LAST COMMENT_BODY TRUE
J 0
(-2075 3000);
DISPLAY 0.872340 (-2075 3000);
PAINT GREEN (-2075 3000);
DISPLAY INVISIBLE (-2075 3000);
FORCEPROP 2 LAST PATH I33
J 0
(-2500 3150);
DISPLAY 1.021277 (-2500 3150);
DISPLAY INVISIBLE (-2500 3150);
FORCEADD OFFPAGE..1
(-2200 2675);
FORCEPROP 2 LAST $XR1 124 
J 0
(-2572 2675);
DISPLAY 0.638298 (-2572 2675);
PAINT MONO (-2572 2675);
FORCEPROP 2 LAST $XR0 216 
J 0
(-2452 2675);
DISPLAY 0.638298 (-2452 2675);
PAINT MONO (-2452 2675);
FORCEPROP 2 LAST CDS_LIB standard
J 0
(-2200 2675);
PAINT MONO (-2200 2675);
DISPLAY INVISIBLE (-2200 2675);
FORCEPROP 1 LAST OFFPAGE TRUE
J 0
(-1875 2550);
DISPLAY 0.872340 (-1875 2550);
PAINT GREEN (-1875 2550);
DISPLAY INVISIBLE (-1875 2550);
FORCEPROP 1 LAST COMMENT_BODY TRUE
J 0
(-2075 2575);
DISPLAY 0.872340 (-2075 2575);
PAINT GREEN (-2075 2575);
DISPLAY INVISIBLE (-2075 2575);
FORCEPROP 2 LAST PATH I34
J 0
(-2500 2725);
DISPLAY 1.021277 (-2500 2725);
DISPLAY INVISIBLE (-2500 2725);
FORCEADD OFFPAGE..1
(-2200 2525);
FORCEPROP 2 LAST $XR1 124 
J 0
(-2572 2525);
DISPLAY 0.638298 (-2572 2525);
PAINT MONO (-2572 2525);
FORCEPROP 2 LAST $XR0 216 
J 0
(-2452 2525);
DISPLAY 0.638298 (-2452 2525);
PAINT MONO (-2452 2525);
FORCEPROP 2 LAST CDS_LIB standard
J 0
(-2200 2525);
PAINT MONO (-2200 2525);
DISPLAY INVISIBLE (-2200 2525);
FORCEPROP 1 LAST OFFPAGE TRUE
J 0
(-1875 2400);
DISPLAY 0.872340 (-1875 2400);
PAINT GREEN (-1875 2400);
DISPLAY INVISIBLE (-1875 2400);
FORCEPROP 1 LAST COMMENT_BODY TRUE
J 0
(-2075 2425);
DISPLAY 0.872340 (-2075 2425);
PAINT GREEN (-2075 2425);
DISPLAY INVISIBLE (-2075 2425);
FORCEPROP 2 LAST PATH I35
J 0
(-2500 2575);
DISPLAY 1.021277 (-2500 2575);
DISPLAY INVISIBLE (-2500 2575);
FORCEADD OFFPAGE..1
(-2200 2375);
FORCEPROP 2 LAST $XR1 124 
J 0
(-2572 2375);
DISPLAY 0.638298 (-2572 2375);
PAINT MONO (-2572 2375);
FORCEPROP 2 LAST $XR0 216 
J 0
(-2452 2375);
DISPLAY 0.638298 (-2452 2375);
PAINT MONO (-2452 2375);
FORCEPROP 2 LAST CDS_LIB standard
J 0
(-2200 2375);
PAINT MONO (-2200 2375);
DISPLAY INVISIBLE (-2200 2375);
FORCEPROP 1 LAST OFFPAGE TRUE
J 0
(-1875 2250);
DISPLAY 0.872340 (-1875 2250);
PAINT GREEN (-1875 2250);
DISPLAY INVISIBLE (-1875 2250);
FORCEPROP 1 LAST COMMENT_BODY TRUE
J 0
(-2075 2275);
DISPLAY 0.872340 (-2075 2275);
PAINT GREEN (-2075 2275);
DISPLAY INVISIBLE (-2075 2275);
FORCEPROP 2 LAST PATH I36
J 0
(-2500 2425);
DISPLAY 1.021277 (-2500 2425);
DISPLAY INVISIBLE (-2500 2425);
FORCEADD OFFPAGE..1
(-2200 2225);
FORCEPROP 2 LAST $XR1 124 
J 0
(-2572 2225);
DISPLAY 0.638298 (-2572 2225);
PAINT MONO (-2572 2225);
FORCEPROP 2 LAST $XR0 216 
J 0
(-2452 2225);
DISPLAY 0.638298 (-2452 2225);
PAINT MONO (-2452 2225);
FORCEPROP 2 LAST CDS_LIB standard
J 0
(-2200 2225);
PAINT MONO (-2200 2225);
DISPLAY INVISIBLE (-2200 2225);
FORCEPROP 1 LAST OFFPAGE TRUE
J 0
(-1875 2100);
DISPLAY 0.872340 (-1875 2100);
PAINT GREEN (-1875 2100);
DISPLAY INVISIBLE (-1875 2100);
FORCEPROP 1 LAST COMMENT_BODY TRUE
J 0
(-2075 2125);
DISPLAY 0.872340 (-2075 2125);
PAINT GREEN (-2075 2125);
DISPLAY INVISIBLE (-2075 2125);
FORCEPROP 2 LAST PATH I37
J 0
(-2500 2275);
DISPLAY 1.021277 (-2500 2275);
DISPLAY INVISIBLE (-2500 2275);
FORCEADD OFFPAGE..1
(-2200 2075);
FORCEPROP 2 LAST $XR1 125 
J 0
(-2572 2075);
DISPLAY 0.638298 (-2572 2075);
PAINT MONO (-2572 2075);
FORCEPROP 2 LAST $XR0 216 
J 0
(-2452 2075);
DISPLAY 0.638298 (-2452 2075);
PAINT MONO (-2452 2075);
FORCEPROP 2 LAST CDS_LIB standard
J 0
(-2200 2075);
PAINT MONO (-2200 2075);
DISPLAY INVISIBLE (-2200 2075);
FORCEPROP 1 LAST OFFPAGE TRUE
J 0
(-1875 1950);
DISPLAY 0.872340 (-1875 1950);
PAINT GREEN (-1875 1950);
DISPLAY INVISIBLE (-1875 1950);
FORCEPROP 1 LAST COMMENT_BODY TRUE
J 0
(-2075 1975);
DISPLAY 0.872340 (-2075 1975);
PAINT GREEN (-2075 1975);
DISPLAY INVISIBLE (-2075 1975);
FORCEPROP 2 LAST PATH I38
J 0
(-2500 2125);
DISPLAY 1.021277 (-2500 2125);
DISPLAY INVISIBLE (-2500 2125);
FORCEADD OFFPAGE..1
(-2200 1925);
FORCEPROP 2 LAST $XR1 125 
J 0
(-2572 1925);
DISPLAY 0.638298 (-2572 1925);
PAINT MONO (-2572 1925);
FORCEPROP 2 LAST $XR0 216 
J 0
(-2452 1925);
DISPLAY 0.638298 (-2452 1925);
PAINT MONO (-2452 1925);
FORCEPROP 2 LAST CDS_LIB standard
J 0
(-2200 1925);
PAINT MONO (-2200 1925);
DISPLAY INVISIBLE (-2200 1925);
FORCEPROP 1 LAST OFFPAGE TRUE
J 0
(-1875 1800);
DISPLAY 0.872340 (-1875 1800);
PAINT GREEN (-1875 1800);
DISPLAY INVISIBLE (-1875 1800);
FORCEPROP 1 LAST COMMENT_BODY TRUE
J 0
(-2075 1825);
DISPLAY 0.872340 (-2075 1825);
PAINT GREEN (-2075 1825);
DISPLAY INVISIBLE (-2075 1825);
FORCEPROP 2 LAST PATH I39
J 0
(-2500 1975);
DISPLAY 1.021277 (-2500 1975);
DISPLAY INVISIBLE (-2500 1975);
FORCEADD Q_RES..1
(-300 4000);
FORCEPROP 1 LAST PART_NUMBER CS22002FB07
J 0
(-475 4100);
DISPLAY 0.638298 (-475 4100);
DISPLAY INVISIBLE (-475 4100);
FORCEPROP 1 LAST VALUE 2K
J 2
(-125 4000);
DISPLAY 0.638298 (-125 4000);
FORCEPROP 1 LAST MATERIAL EMPTY
J 0
(0 4000);
DISPLAY 0.638298 (0 4000);
PAINT RED (0 4000);
FORCEPROP 1 LAST PACK_TYPE 0402LF
J 0
(-475 4150);
DISPLAY 0.638298 (-475 4150);
FORCEPROP 1 LAST WATTAGE 1/16W
J 2
(-100 4150);
DISPLAY 0.638298 (-100 4150);
FORCEPROP 1 LAST TOLERANCE 1%
J 0
(-100 4000);
DISPLAY 0.638298 (-100 4000);
FORCEPROP 1 LAST $LOCATION R1415
J 0
(-625 4000);
DISPLAY 0.787234 (-625 4000);
FORCEPROP 1 LASTPIN (-400 4000) $PN 1
J 0
(-388 4012);
DISPLAY 0.787234 (-388 4012);
FORCEPROP 1 LASTPIN (-200 4000) $PN 2
J 0
(-238 4012);
DISPLAY 0.787234 (-238 4012);
FORCEPROP 2 LAST CDS_LIB pure_quanta
J 0
(-300 4000);
PAINT MONO (-300 4000);
DISPLAY INVISIBLE (-300 4000);
FORCEPROP 1 LAST PATH I4
J 0
(-350 4150);
DISPLAY 0.978723 (-350 4150);
PAINT WHITE (-350 4150);
DISPLAY INVISIBLE (-350 4150);
FORCEPROP 2 LAST CDS_LOCATION R1415
J 0
(-100 4200);
DISPLAY 1.021277 (-100 4200);
DISPLAY INVISIBLE (-100 4200);
FORCEPROP 2 LAST $SEC 1
J 0
(-100 4200);
DISPLAY 0.680851 (-100 4200);
PAINT MONO (-100 4200);
DISPLAY INVISIBLE (-100 4200);
FORCEPROP 2 LAST CDS_SEC 1
J 0
(-100 4200);
DISPLAY 1.021277 (-100 4200);
DISPLAY INVISIBLE (-100 4200);
FORCEADD OFFPAGE..1
(-2200 1775);
FORCEPROP 2 LAST $XR1 125 
J 0
(-2572 1775);
DISPLAY 0.638298 (-2572 1775);
PAINT MONO (-2572 1775);
FORCEPROP 2 LAST $XR0 216 
J 0
(-2452 1775);
DISPLAY 0.638298 (-2452 1775);
PAINT MONO (-2452 1775);
FORCEPROP 2 LAST CDS_LIB standard
J 0
(-2200 1775);
PAINT MONO (-2200 1775);
DISPLAY INVISIBLE (-2200 1775);
FORCEPROP 1 LAST OFFPAGE TRUE
J 0
(-1875 1650);
DISPLAY 0.872340 (-1875 1650);
PAINT GREEN (-1875 1650);
DISPLAY INVISIBLE (-1875 1650);
FORCEPROP 1 LAST COMMENT_BODY TRUE
J 0
(-2075 1675);
DISPLAY 0.872340 (-2075 1675);
PAINT GREEN (-2075 1675);
DISPLAY INVISIBLE (-2075 1675);
FORCEPROP 2 LAST PATH I40
J 0
(-2500 1825);
DISPLAY 1.021277 (-2500 1825);
DISPLAY INVISIBLE (-2500 1825);
FORCEADD OFFPAGE..1
(-2200 1625);
FORCEPROP 2 LAST $XR1 125 
J 0
(-2572 1625);
DISPLAY 0.638298 (-2572 1625);
PAINT MONO (-2572 1625);
FORCEPROP 2 LAST $XR0 216 
J 0
(-2452 1625);
DISPLAY 0.638298 (-2452 1625);
PAINT MONO (-2452 1625);
FORCEPROP 2 LAST CDS_LIB standard
J 0
(-2200 1625);
PAINT MONO (-2200 1625);
DISPLAY INVISIBLE (-2200 1625);
FORCEPROP 1 LAST OFFPAGE TRUE
J 0
(-1875 1500);
DISPLAY 0.872340 (-1875 1500);
PAINT GREEN (-1875 1500);
DISPLAY INVISIBLE (-1875 1500);
FORCEPROP 1 LAST COMMENT_BODY TRUE
J 0
(-2075 1525);
DISPLAY 0.872340 (-2075 1525);
PAINT GREEN (-2075 1525);
DISPLAY INVISIBLE (-2075 1525);
FORCEPROP 2 LAST PATH I41
J 0
(-2500 1675);
DISPLAY 1.021277 (-2500 1675);
DISPLAY INVISIBLE (-2500 1675);
FORCEADD OFFPAGE..1
(-2200 1250);
FORCEPROP 2 LAST $XR1 223 
J 0
(-2572 1250);
DISPLAY 0.638298 (-2572 1250);
PAINT MONO (-2572 1250);
FORCEPROP 2 LAST $XR0 215 
J 0
(-2452 1250);
DISPLAY 0.638298 (-2452 1250);
PAINT MONO (-2452 1250);
FORCEPROP 2 LAST CDS_LIB standard
J 0
(-2200 1250);
PAINT MONO (-2200 1250);
DISPLAY INVISIBLE (-2200 1250);
FORCEPROP 1 LAST OFFPAGE TRUE
J 0
(-1875 1125);
DISPLAY 0.872340 (-1875 1125);
PAINT GREEN (-1875 1125);
DISPLAY INVISIBLE (-1875 1125);
FORCEPROP 1 LAST COMMENT_BODY TRUE
J 0
(-2075 1150);
DISPLAY 0.872340 (-2075 1150);
PAINT GREEN (-2075 1150);
DISPLAY INVISIBLE (-2075 1150);
FORCEPROP 2 LAST PATH I42
J 0
(-2500 1300);
DISPLAY 1.021277 (-2500 1300);
DISPLAY INVISIBLE (-2500 1300);
FORCEADD OFFPAGE..1
(-2200 1100);
FORCEPROP 2 LAST $XR0 214 
J 0
(-2452 1100);
DISPLAY 0.638298 (-2452 1100);
PAINT MONO (-2452 1100);
FORCEPROP 2 LAST CDS_LIB standard
J 0
(-2200 1100);
PAINT MONO (-2200 1100);
DISPLAY INVISIBLE (-2200 1100);
FORCEPROP 1 LAST OFFPAGE TRUE
J 0
(-1875 975);
DISPLAY 0.872340 (-1875 975);
PAINT GREEN (-1875 975);
DISPLAY INVISIBLE (-1875 975);
FORCEPROP 1 LAST COMMENT_BODY TRUE
J 0
(-2075 1000);
DISPLAY 0.872340 (-2075 1000);
PAINT GREEN (-2075 1000);
DISPLAY INVISIBLE (-2075 1000);
FORCEPROP 2 LAST PATH I43
J 0
(-2500 1150);
DISPLAY 1.021277 (-2500 1150);
DISPLAY INVISIBLE (-2500 1150);
FORCEADD OFFPAGE..1
(-2200 950);
FORCEPROP 2 LAST $XR1 124 
J 0
(-2572 950);
DISPLAY 0.638298 (-2572 950);
PAINT MONO (-2572 950);
FORCEPROP 2 LAST $XR0 216 
J 0
(-2452 950);
DISPLAY 0.638298 (-2452 950);
PAINT MONO (-2452 950);
FORCEPROP 2 LAST CDS_LIB standard
J 0
(-2200 950);
PAINT MONO (-2200 950);
DISPLAY INVISIBLE (-2200 950);
FORCEPROP 1 LAST OFFPAGE TRUE
J 0
(-1875 825);
DISPLAY 0.872340 (-1875 825);
PAINT GREEN (-1875 825);
DISPLAY INVISIBLE (-1875 825);
FORCEPROP 1 LAST COMMENT_BODY TRUE
J 0
(-2075 850);
DISPLAY 0.872340 (-2075 850);
PAINT GREEN (-2075 850);
DISPLAY INVISIBLE (-2075 850);
FORCEPROP 2 LAST PATH I44
J 0
(-2500 1000);
DISPLAY 1.021277 (-2500 1000);
DISPLAY INVISIBLE (-2500 1000);
FORCEADD OFFPAGE..1
(-2200 800);
FORCEPROP 2 LAST $XR1 125 
J 0
(-2572 800);
DISPLAY 0.638298 (-2572 800);
PAINT MONO (-2572 800);
FORCEPROP 2 LAST $XR0 216 
J 0
(-2452 800);
DISPLAY 0.638298 (-2452 800);
PAINT MONO (-2452 800);
FORCEPROP 2 LAST CDS_LIB standard
J 0
(-2200 800);
PAINT MONO (-2200 800);
DISPLAY INVISIBLE (-2200 800);
FORCEPROP 1 LAST OFFPAGE TRUE
J 0
(-1875 675);
DISPLAY 0.872340 (-1875 675);
PAINT GREEN (-1875 675);
DISPLAY INVISIBLE (-1875 675);
FORCEPROP 1 LAST COMMENT_BODY TRUE
J 0
(-2075 700);
DISPLAY 0.872340 (-2075 700);
PAINT GREEN (-2075 700);
DISPLAY INVISIBLE (-2075 700);
FORCEPROP 2 LAST PATH I45
J 0
(-2500 850);
DISPLAY 1.021277 (-2500 850);
DISPLAY INVISIBLE (-2500 850);
FORCEADD OFFPAGE..1
(-2200 650);
FORCEPROP 2 LAST $XR2 240 
J 0
(-2692 650);
DISPLAY 0.638298 (-2692 650);
PAINT MONO (-2692 650);
FORCEPROP 2 LAST $XR1 182 
J 0
(-2572 650);
DISPLAY 0.638298 (-2572 650);
PAINT MONO (-2572 650);
FORCEPROP 2 LAST $XR0 222 
J 0
(-2452 650);
DISPLAY 0.638298 (-2452 650);
PAINT MONO (-2452 650);
FORCEPROP 2 LAST CDS_LIB standard
J 0
(-2200 650);
PAINT MONO (-2200 650);
DISPLAY INVISIBLE (-2200 650);
FORCEPROP 1 LAST OFFPAGE TRUE
J 0
(-1875 525);
DISPLAY 0.872340 (-1875 525);
PAINT GREEN (-1875 525);
DISPLAY INVISIBLE (-1875 525);
FORCEPROP 1 LAST COMMENT_BODY TRUE
J 0
(-2075 550);
DISPLAY 0.872340 (-2075 550);
PAINT GREEN (-2075 550);
DISPLAY INVISIBLE (-2075 550);
FORCEPROP 2 LAST PATH I46
J 0
(-2500 700);
DISPLAY 1.021277 (-2500 700);
DISPLAY INVISIBLE (-2500 700);
FORCEADD OFFPAGE..1
(-2200 500);
FORCEPROP 2 LAST $XR1 182 
J 0
(-2572 500);
DISPLAY 0.638298 (-2572 500);
PAINT MONO (-2572 500);
FORCEPROP 2 LAST $XR0 222 
J 0
(-2452 500);
DISPLAY 0.638298 (-2452 500);
PAINT MONO (-2452 500);
FORCEPROP 2 LAST CDS_LIB standard
J 0
(-2200 500);
PAINT MONO (-2200 500);
DISPLAY INVISIBLE (-2200 500);
FORCEPROP 1 LAST OFFPAGE TRUE
J 0
(-1875 375);
DISPLAY 0.872340 (-1875 375);
PAINT GREEN (-1875 375);
DISPLAY INVISIBLE (-1875 375);
FORCEPROP 1 LAST COMMENT_BODY TRUE
J 0
(-2075 400);
DISPLAY 0.872340 (-2075 400);
PAINT GREEN (-2075 400);
DISPLAY INVISIBLE (-2075 400);
FORCEPROP 2 LAST PATH I47
J 0
(-2500 550);
DISPLAY 1.021277 (-2500 550);
DISPLAY INVISIBLE (-2500 550);
FORCEADD OFFPAGE..1
(-2200 350);
FORCEPROP 2 LAST $XR1 263 
J 0
(-2572 350);
DISPLAY 0.638298 (-2572 350);
PAINT MONO (-2572 350);
FORCEPROP 2 LAST $XR0 214 
J 0
(-2452 350);
DISPLAY 0.638298 (-2452 350);
PAINT MONO (-2452 350);
FORCEPROP 2 LAST CDS_LIB standard
J 0
(-2200 350);
PAINT MONO (-2200 350);
DISPLAY INVISIBLE (-2200 350);
FORCEPROP 1 LAST OFFPAGE TRUE
J 0
(-1875 225);
DISPLAY 0.872340 (-1875 225);
PAINT GREEN (-1875 225);
DISPLAY INVISIBLE (-1875 225);
FORCEPROP 1 LAST COMMENT_BODY TRUE
J 0
(-2075 250);
DISPLAY 0.872340 (-2075 250);
PAINT GREEN (-2075 250);
DISPLAY INVISIBLE (-2075 250);
FORCEPROP 2 LAST PATH I48
J 0
(-2500 400);
DISPLAY 1.021277 (-2500 400);
DISPLAY INVISIBLE (-2500 400);
FORCEADD OFFPAGE..1
(-2200 200);
FORCEPROP 2 LAST $XR1 222 
J 0
(-2572 200);
DISPLAY 0.638298 (-2572 200);
PAINT MONO (-2572 200);
FORCEPROP 2 LAST $XR0 214 
J 0
(-2452 200);
DISPLAY 0.638298 (-2452 200);
PAINT MONO (-2452 200);
FORCEPROP 2 LAST CDS_LIB standard
J 0
(-2200 200);
PAINT MONO (-2200 200);
DISPLAY INVISIBLE (-2200 200);
FORCEPROP 1 LAST OFFPAGE TRUE
J 0
(-1875 75);
DISPLAY 0.872340 (-1875 75);
PAINT GREEN (-1875 75);
DISPLAY INVISIBLE (-1875 75);
FORCEPROP 1 LAST COMMENT_BODY TRUE
J 0
(-2075 100);
DISPLAY 0.872340 (-2075 100);
PAINT GREEN (-2075 100);
DISPLAY INVISIBLE (-2075 100);
FORCEPROP 2 LAST PATH I49
J 0
(-2500 250);
DISPLAY 1.021277 (-2500 250);
DISPLAY INVISIBLE (-2500 250);
FORCEADD Q_RES..1
(-300 3850);
FORCEPROP 1 LAST PART_NUMBER CS22002FB07
J 0
(-475 3950);
DISPLAY 0.638298 (-475 3950);
DISPLAY INVISIBLE (-475 3950);
FORCEPROP 1 LAST TOLERANCE 1%
J 0
(-100 3850);
DISPLAY 0.638298 (-100 3850);
FORCEPROP 1 LAST MATERIAL EMPTY
J 0
(0 3850);
DISPLAY 0.638298 (0 3850);
PAINT RED (0 3850);
FORCEPROP 1 LAST VALUE 2K
J 2
(-125 3850);
DISPLAY 0.638298 (-125 3850);
FORCEPROP 1 LAST $LOCATION R1416
J 0
(-625 3850);
DISPLAY 0.787234 (-625 3850);
FORCEPROP 1 LASTPIN (-400 3850) $PN 1
J 0
(-388 3862);
DISPLAY 0.787234 (-388 3862);
FORCEPROP 1 LASTPIN (-200 3850) $PN 2
J 0
(-238 3862);
DISPLAY 0.787234 (-238 3862);
FORCEPROP 1 LAST WATTAGE 1/16W
J 2
(-100 4000);
DISPLAY 0.638298 (-100 4000);
DISPLAY INVISIBLE (-100 4000);
FORCEPROP 1 LAST PACK_TYPE 0402LF
J 0
(-475 4000);
DISPLAY 0.638298 (-475 4000);
DISPLAY INVISIBLE (-475 4000);
FORCEPROP 2 LAST CDS_LIB pure_quanta
J 0
(-300 3850);
PAINT MONO (-300 3850);
DISPLAY INVISIBLE (-300 3850);
FORCEPROP 1 LAST PATH I5
J 0
(-350 4000);
DISPLAY 0.978723 (-350 4000);
PAINT WHITE (-350 4000);
DISPLAY INVISIBLE (-350 4000);
FORCEPROP 2 LAST CDS_LOCATION R1416
J 0
(-350 4050);
DISPLAY 1.021277 (-350 4050);
DISPLAY INVISIBLE (-350 4050);
FORCEPROP 2 LAST $SEC 1
J 0
(-350 4050);
DISPLAY 0.680851 (-350 4050);
PAINT MONO (-350 4050);
DISPLAY INVISIBLE (-350 4050);
FORCEPROP 2 LAST CDS_SEC 1
J 0
(-350 4050);
DISPLAY 1.021277 (-350 4050);
DISPLAY INVISIBLE (-350 4050);
FORCEADD UNIVERSAL_GND..1
(250 -1325);
FORCEPROP 3 LASTPIN (250 -1275) SIG_NAME GND\g
J 0
(260 -1265);
DISPLAY 0.659574 (260 -1265);
PAINT MONO (260 -1265);
DISPLAY INVISIBLE (260 -1265);
FORCEPROP 2 LAST CDS_LIB logical_power
J 0
(250 -1325);
PAINT MONO (250 -1325);
DISPLAY INVISIBLE (250 -1325);
FORCEPROP 1 LAST HDL_POWER GND
J 1
(275 -1400);
DISPLAY 0.872340 (275 -1400);
PAINT GREEN (275 -1400);
DISPLAY INVISIBLE (275 -1400);
FORCEPROP 1 LAST PATH I50
J 0
(325 -1325);
DISPLAY 0.872340 (325 -1325);
PAINT AQUA (325 -1325);
DISPLAY INVISIBLE (325 -1325);
FORCEPROP 2 LAST ROOM IO_SLOT
J 1
(25 -1250);
DISPLAY 0.744681 (25 -1250);
DISPLAY INVISIBLE (25 -1250);
FORCEADD Q_RES..1
(-300 50);
FORCEPROP 1 LAST PART_NUMBER CS22002FB07
J 0
(-475 150);
DISPLAY 0.638298 (-475 150);
DISPLAY INVISIBLE (-475 150);
FORCEPROP 1 LAST VALUE 2K
J 2
(-125 50);
DISPLAY 0.638298 (-125 50);
FORCEPROP 1 LAST TOLERANCE 1%
J 0
(-100 50);
DISPLAY 0.638298 (-100 50);
FORCEPROP 1 LAST MATERIAL CHIP
J 0
(0 50);
DISPLAY 0.638298 (0 50);
FORCEPROP 1 LAST $LOCATION R1406
J 0
(-625 50);
DISPLAY 0.787234 (-625 50);
FORCEPROP 1 LASTPIN (-400 50) $PN 1
J 0
(-388 62);
DISPLAY 0.787234 (-388 62);
FORCEPROP 1 LASTPIN (-200 50) $PN 2
J 0
(-238 62);
DISPLAY 0.787234 (-238 62);
FORCEPROP 1 LAST WATTAGE 1/16W
J 2
(-100 200);
DISPLAY 0.638298 (-100 200);
DISPLAY INVISIBLE (-100 200);
FORCEPROP 1 LAST PACK_TYPE 0402LF
J 0
(-475 200);
DISPLAY 0.638298 (-475 200);
DISPLAY INVISIBLE (-475 200);
FORCEPROP 2 LAST CDS_LIB pure_quanta
J 0
(-300 50);
PAINT MONO (-300 50);
DISPLAY INVISIBLE (-300 50);
FORCEPROP 1 LAST PATH I51
J 0
(-350 200);
DISPLAY 0.978723 (-350 200);
PAINT WHITE (-350 200);
DISPLAY INVISIBLE (-350 200);
FORCEPROP 2 LAST CDS_LOCATION R1406
J 0
(-350 250);
DISPLAY 1.021277 (-350 250);
DISPLAY INVISIBLE (-350 250);
FORCEPROP 2 LAST $SEC 1
J 0
(-350 250);
DISPLAY 0.680851 (-350 250);
PAINT MONO (-350 250);
DISPLAY INVISIBLE (-350 250);
FORCEPROP 2 LAST CDS_SEC 1
J 0
(-350 250);
DISPLAY 1.021277 (-350 250);
DISPLAY INVISIBLE (-350 250);
FORCEADD Q_RES..1
(-300 -100);
FORCEPROP 1 LAST PART_NUMBER CS22002FB07
J 0
(-475 0);
DISPLAY 0.638298 (-475 0);
DISPLAY INVISIBLE (-475 0);
FORCEPROP 1 LAST TOLERANCE 1%
J 0
(-100 -100);
DISPLAY 0.638298 (-100 -100);
FORCEPROP 1 LAST VALUE 2K
J 2
(-125 -100);
DISPLAY 0.638298 (-125 -100);
FORCEPROP 1 LAST MATERIAL CHIP
J 0
(0 -100);
DISPLAY 0.638298 (0 -100);
FORCEPROP 1 LAST $LOCATION R1407
J 0
(-625 -100);
DISPLAY 0.787234 (-625 -100);
FORCEPROP 1 LASTPIN (-400 -100) $PN 1
J 0
(-388 -88);
DISPLAY 0.787234 (-388 -88);
FORCEPROP 1 LASTPIN (-200 -100) $PN 2
J 0
(-238 -88);
DISPLAY 0.787234 (-238 -88);
FORCEPROP 2 LAST CDS_LIB pure_quanta
J 0
(-300 -100);
PAINT MONO (-300 -100);
DISPLAY INVISIBLE (-300 -100);
FORCEPROP 1 LAST PACK_TYPE 0402LF
J 0
(-475 50);
DISPLAY 0.638298 (-475 50);
DISPLAY INVISIBLE (-475 50);
FORCEPROP 1 LAST WATTAGE 1/16W
J 2
(-100 50);
DISPLAY 0.638298 (-100 50);
DISPLAY INVISIBLE (-100 50);
FORCEPROP 1 LAST PATH I52
J 0
(-350 50);
DISPLAY 0.978723 (-350 50);
PAINT WHITE (-350 50);
DISPLAY INVISIBLE (-350 50);
FORCEPROP 2 LAST CDS_LOCATION R1407
J 0
(-350 100);
DISPLAY 1.021277 (-350 100);
DISPLAY INVISIBLE (-350 100);
FORCEPROP 2 LAST $SEC 1
J 0
(-350 100);
DISPLAY 0.680851 (-350 100);
PAINT MONO (-350 100);
DISPLAY INVISIBLE (-350 100);
FORCEPROP 2 LAST CDS_SEC 1
J 0
(-350 100);
DISPLAY 1.021277 (-350 100);
DISPLAY INVISIBLE (-350 100);
FORCEADD Q_RES..1
(-300 -250);
FORCEPROP 1 LAST PART_NUMBER CS22002FB07
J 0
(-475 -150);
DISPLAY 0.638298 (-475 -150);
DISPLAY INVISIBLE (-475 -150);
FORCEPROP 1 LAST VALUE 2K
J 2
(-125 -250);
DISPLAY 0.638298 (-125 -250);
FORCEPROP 1 LAST TOLERANCE 1%
J 0
(-100 -250);
DISPLAY 0.638298 (-100 -250);
FORCEPROP 1 LAST MATERIAL CHIP
J 0
(0 -250);
DISPLAY 0.638298 (0 -250);
FORCEPROP 1 LAST $LOCATION R1408
J 0
(-625 -250);
DISPLAY 0.787234 (-625 -250);
FORCEPROP 1 LASTPIN (-400 -250) $PN 1
J 0
(-388 -238);
DISPLAY 0.787234 (-388 -238);
FORCEPROP 1 LASTPIN (-200 -250) $PN 2
J 0
(-238 -238);
DISPLAY 0.787234 (-238 -238);
FORCEPROP 1 LAST WATTAGE 1/16W
J 2
(-100 -100);
DISPLAY 0.638298 (-100 -100);
DISPLAY INVISIBLE (-100 -100);
FORCEPROP 1 LAST PACK_TYPE 0402LF
J 0
(-475 -100);
DISPLAY 0.638298 (-475 -100);
DISPLAY INVISIBLE (-475 -100);
FORCEPROP 2 LAST CDS_LIB pure_quanta
J 0
(-300 -250);
PAINT MONO (-300 -250);
DISPLAY INVISIBLE (-300 -250);
FORCEPROP 1 LAST PATH I53
J 0
(-350 -100);
DISPLAY 0.978723 (-350 -100);
PAINT WHITE (-350 -100);
DISPLAY INVISIBLE (-350 -100);
FORCEPROP 2 LAST CDS_LOCATION R1408
J 0
(-350 -50);
DISPLAY 1.021277 (-350 -50);
DISPLAY INVISIBLE (-350 -50);
FORCEPROP 2 LAST $SEC 1
J 0
(-350 -50);
DISPLAY 0.680851 (-350 -50);
PAINT MONO (-350 -50);
DISPLAY INVISIBLE (-350 -50);
FORCEPROP 2 LAST CDS_SEC 1
J 0
(-350 -50);
DISPLAY 1.021277 (-350 -50);
DISPLAY INVISIBLE (-350 -50);
FORCEADD Q_RES..1
(-300 -550);
FORCEPROP 1 LAST PART_NUMBER CS22002FB07
J 0
(-475 -450);
DISPLAY 0.638298 (-475 -450);
DISPLAY INVISIBLE (-475 -450);
FORCEPROP 1 LAST MATERIAL CHIP
J 0
(0 -550);
DISPLAY 0.638298 (0 -550);
FORCEPROP 1 LAST VALUE 2K
J 2
(-125 -550);
DISPLAY 0.638298 (-125 -550);
FORCEPROP 1 LAST TOLERANCE 1%
J 0
(-100 -550);
DISPLAY 0.638298 (-100 -550);
FORCEPROP 1 LAST $LOCATION R1410
J 0
(-625 -550);
DISPLAY 0.787234 (-625 -550);
FORCEPROP 1 LASTPIN (-400 -550) $PN 1
J 0
(-388 -538);
DISPLAY 0.787234 (-388 -538);
FORCEPROP 1 LASTPIN (-200 -550) $PN 2
J 0
(-238 -538);
DISPLAY 0.787234 (-238 -538);
FORCEPROP 1 LAST WATTAGE 1/16W
J 2
(-100 -400);
DISPLAY 0.638298 (-100 -400);
DISPLAY INVISIBLE (-100 -400);
FORCEPROP 1 LAST PACK_TYPE 0402LF
J 0
(-475 -400);
DISPLAY 0.638298 (-475 -400);
DISPLAY INVISIBLE (-475 -400);
FORCEPROP 2 LAST CDS_LIB pure_quanta
J 0
(-300 -550);
PAINT MONO (-300 -550);
DISPLAY INVISIBLE (-300 -550);
FORCEPROP 1 LAST PATH I54
J 0
(-350 -400);
DISPLAY 0.978723 (-350 -400);
PAINT WHITE (-350 -400);
DISPLAY INVISIBLE (-350 -400);
FORCEPROP 2 LAST CDS_LOCATION R1410
J 0
(-350 -350);
DISPLAY 1.021277 (-350 -350);
DISPLAY INVISIBLE (-350 -350);
FORCEPROP 2 LAST $SEC 1
J 0
(-350 -350);
DISPLAY 0.680851 (-350 -350);
PAINT MONO (-350 -350);
DISPLAY INVISIBLE (-350 -350);
FORCEPROP 2 LAST CDS_SEC 1
J 0
(-350 -350);
DISPLAY 1.021277 (-350 -350);
DISPLAY INVISIBLE (-350 -350);
FORCEADD Q_RES..1
(-300 -400);
FORCEPROP 1 LAST PART_NUMBER CS22002FB07
J 0
(-475 -300);
DISPLAY 0.638298 (-475 -300);
DISPLAY INVISIBLE (-475 -300);
FORCEPROP 1 LAST TOLERANCE 1%
J 0
(-100 -400);
DISPLAY 0.638298 (-100 -400);
FORCEPROP 1 LAST VALUE 2K
J 2
(-125 -400);
DISPLAY 0.638298 (-125 -400);
FORCEPROP 1 LAST MATERIAL CHIP
J 0
(0 -400);
DISPLAY 0.638298 (0 -400);
FORCEPROP 1 LAST $LOCATION R1409
J 0
(-625 -400);
DISPLAY 0.787234 (-625 -400);
FORCEPROP 1 LASTPIN (-400 -400) $PN 1
J 0
(-388 -388);
DISPLAY 0.787234 (-388 -388);
FORCEPROP 1 LASTPIN (-200 -400) $PN 2
J 0
(-238 -388);
DISPLAY 0.787234 (-238 -388);
FORCEPROP 2 LAST CDS_LIB pure_quanta
J 0
(-300 -400);
PAINT MONO (-300 -400);
DISPLAY INVISIBLE (-300 -400);
FORCEPROP 1 LAST PACK_TYPE 0402LF
J 0
(-475 -250);
DISPLAY 0.638298 (-475 -250);
DISPLAY INVISIBLE (-475 -250);
FORCEPROP 1 LAST WATTAGE 1/16W
J 2
(-100 -250);
DISPLAY 0.638298 (-100 -250);
DISPLAY INVISIBLE (-100 -250);
FORCEPROP 1 LAST PATH I55
J 0
(-350 -250);
DISPLAY 0.978723 (-350 -250);
PAINT WHITE (-350 -250);
DISPLAY INVISIBLE (-350 -250);
FORCEPROP 2 LAST CDS_LOCATION R1409
J 0
(-350 -200);
DISPLAY 1.021277 (-350 -200);
DISPLAY INVISIBLE (-350 -200);
FORCEPROP 2 LAST $SEC 1
J 0
(-350 -200);
DISPLAY 0.680851 (-350 -200);
PAINT MONO (-350 -200);
DISPLAY INVISIBLE (-350 -200);
FORCEPROP 2 LAST CDS_SEC 1
J 0
(-350 -200);
DISPLAY 1.021277 (-350 -200);
DISPLAY INVISIBLE (-350 -200);
FORCEADD Q_RES..1
(-300 -700);
FORCEPROP 1 LAST PART_NUMBER CS22002FB07
J 0
(-475 -600);
DISPLAY 0.638298 (-475 -600);
DISPLAY INVISIBLE (-475 -600);
FORCEPROP 1 LAST TOLERANCE 1%
J 0
(-100 -700);
DISPLAY 0.638298 (-100 -700);
FORCEPROP 1 LAST VALUE 2K
J 2
(-125 -700);
DISPLAY 0.638298 (-125 -700);
FORCEPROP 1 LAST MATERIAL CHIP
J 0
(0 -700);
DISPLAY 0.638298 (0 -700);
FORCEPROP 1 LAST $LOCATION R1411
J 0
(-625 -700);
DISPLAY 0.787234 (-625 -700);
FORCEPROP 1 LASTPIN (-400 -700) $PN 1
J 0
(-388 -688);
DISPLAY 0.787234 (-388 -688);
FORCEPROP 1 LASTPIN (-200 -700) $PN 2
J 0
(-238 -688);
DISPLAY 0.787234 (-238 -688);
FORCEPROP 2 LAST CDS_LIB pure_quanta
J 0
(-300 -700);
PAINT MONO (-300 -700);
DISPLAY INVISIBLE (-300 -700);
FORCEPROP 1 LAST PACK_TYPE 0402LF
J 0
(-475 -550);
DISPLAY 0.638298 (-475 -550);
DISPLAY INVISIBLE (-475 -550);
FORCEPROP 1 LAST WATTAGE 1/16W
J 2
(-100 -550);
DISPLAY 0.638298 (-100 -550);
DISPLAY INVISIBLE (-100 -550);
FORCEPROP 1 LAST PATH I56
J 0
(-350 -550);
DISPLAY 0.978723 (-350 -550);
PAINT WHITE (-350 -550);
DISPLAY INVISIBLE (-350 -550);
FORCEPROP 2 LAST CDS_LOCATION R1411
J 0
(-350 -500);
DISPLAY 1.021277 (-350 -500);
DISPLAY INVISIBLE (-350 -500);
FORCEPROP 2 LAST $SEC 1
J 0
(-350 -500);
DISPLAY 0.680851 (-350 -500);
PAINT MONO (-350 -500);
DISPLAY INVISIBLE (-350 -500);
FORCEPROP 2 LAST CDS_SEC 1
J 0
(-350 -500);
DISPLAY 1.021277 (-350 -500);
DISPLAY INVISIBLE (-350 -500);
FORCEADD Q_RES..1
(-300 -850);
FORCEPROP 1 LAST PART_NUMBER CS22002FB07
J 0
(-475 -750);
DISPLAY 0.638298 (-475 -750);
DISPLAY INVISIBLE (-475 -750);
FORCEPROP 1 LAST VALUE 2K
J 2
(-125 -850);
DISPLAY 0.638298 (-125 -850);
FORCEPROP 1 LAST MATERIAL CHIP
J 0
(0 -850);
DISPLAY 0.638298 (0 -850);
FORCEPROP 1 LAST TOLERANCE 1%
J 0
(-100 -850);
DISPLAY 0.638298 (-100 -850);
FORCEPROP 1 LAST $LOCATION R1412
J 0
(-625 -850);
DISPLAY 0.787234 (-625 -850);
FORCEPROP 1 LASTPIN (-400 -850) $PN 1
J 0
(-388 -838);
DISPLAY 0.787234 (-388 -838);
FORCEPROP 1 LASTPIN (-200 -850) $PN 2
J 0
(-238 -838);
DISPLAY 0.787234 (-238 -838);
FORCEPROP 1 LAST WATTAGE 1/16W
J 2
(-100 -700);
DISPLAY 0.638298 (-100 -700);
DISPLAY INVISIBLE (-100 -700);
FORCEPROP 1 LAST PACK_TYPE 0402LF
J 0
(-475 -700);
DISPLAY 0.638298 (-475 -700);
DISPLAY INVISIBLE (-475 -700);
FORCEPROP 2 LAST CDS_LIB pure_quanta
J 0
(-300 -850);
PAINT MONO (-300 -850);
DISPLAY INVISIBLE (-300 -850);
FORCEPROP 1 LAST PATH I57
J 0
(-350 -700);
DISPLAY 0.978723 (-350 -700);
PAINT WHITE (-350 -700);
DISPLAY INVISIBLE (-350 -700);
FORCEPROP 2 LAST CDS_LOCATION R1412
J 0
(-350 -650);
DISPLAY 1.021277 (-350 -650);
DISPLAY INVISIBLE (-350 -650);
FORCEPROP 2 LAST $SEC 1
J 0
(-350 -650);
DISPLAY 0.680851 (-350 -650);
PAINT MONO (-350 -650);
DISPLAY INVISIBLE (-350 -650);
FORCEPROP 2 LAST CDS_SEC 1
J 0
(-350 -650);
DISPLAY 1.021277 (-350 -650);
DISPLAY INVISIBLE (-350 -650);
FORCEADD Q_RES..1
(-300 -1150);
FORCEPROP 1 LAST PART_NUMBER CS22002FB07
J 0
(-475 -1050);
DISPLAY 0.638298 (-475 -1050);
DISPLAY INVISIBLE (-475 -1050);
FORCEPROP 1 LAST TOLERANCE 1%
J 0
(-100 -1150);
DISPLAY 0.638298 (-100 -1150);
FORCEPROP 1 LAST MATERIAL CHIP
J 0
(0 -1150);
DISPLAY 0.638298 (0 -1150);
FORCEPROP 1 LAST VALUE 2K
J 2
(-125 -1150);
DISPLAY 0.638298 (-125 -1150);
FORCEPROP 1 LAST $LOCATION R1414
J 0
(-625 -1150);
DISPLAY 0.787234 (-625 -1150);
FORCEPROP 1 LASTPIN (-400 -1150) $PN 1
J 0
(-388 -1138);
DISPLAY 0.787234 (-388 -1138);
FORCEPROP 1 LASTPIN (-200 -1150) $PN 2
J 0
(-238 -1138);
DISPLAY 0.787234 (-238 -1138);
FORCEPROP 1 LAST WATTAGE 1/16W
J 2
(-100 -1000);
DISPLAY 0.638298 (-100 -1000);
DISPLAY INVISIBLE (-100 -1000);
FORCEPROP 1 LAST PACK_TYPE 0402LF
J 0
(-475 -1000);
DISPLAY 0.638298 (-475 -1000);
DISPLAY INVISIBLE (-475 -1000);
FORCEPROP 2 LAST CDS_LIB pure_quanta
J 0
(-300 -1150);
PAINT MONO (-300 -1150);
DISPLAY INVISIBLE (-300 -1150);
FORCEPROP 1 LAST PATH I58
J 0
(-350 -1000);
DISPLAY 0.978723 (-350 -1000);
PAINT WHITE (-350 -1000);
DISPLAY INVISIBLE (-350 -1000);
FORCEPROP 2 LAST CDS_LOCATION R1414
J 0
(-350 -950);
DISPLAY 1.021277 (-350 -950);
DISPLAY INVISIBLE (-350 -950);
FORCEPROP 2 LAST $SEC 1
J 0
(-350 -950);
DISPLAY 0.680851 (-350 -950);
PAINT MONO (-350 -950);
DISPLAY INVISIBLE (-350 -950);
FORCEPROP 2 LAST CDS_SEC 1
J 0
(-350 -950);
DISPLAY 1.021277 (-350 -950);
DISPLAY INVISIBLE (-350 -950);
FORCEADD Q_RES..1
(-300 -1000);
FORCEPROP 1 LAST PART_NUMBER CS22002FB07
J 0
(-475 -900);
DISPLAY 0.638298 (-475 -900);
DISPLAY INVISIBLE (-475 -900);
FORCEPROP 1 LAST TOLERANCE 1%
J 0
(-100 -1000);
DISPLAY 0.638298 (-100 -1000);
FORCEPROP 1 LAST VALUE 2K
J 2
(-125 -1000);
DISPLAY 0.638298 (-125 -1000);
FORCEPROP 1 LAST MATERIAL CHIP
J 0
(0 -1000);
DISPLAY 0.638298 (0 -1000);
FORCEPROP 1 LAST $LOCATION R1413
J 0
(-625 -1000);
DISPLAY 0.787234 (-625 -1000);
FORCEPROP 1 LASTPIN (-400 -1000) $PN 1
J 0
(-388 -988);
DISPLAY 0.787234 (-388 -988);
FORCEPROP 1 LASTPIN (-200 -1000) $PN 2
J 0
(-238 -988);
DISPLAY 0.787234 (-238 -988);
FORCEPROP 2 LAST CDS_LIB pure_quanta
J 0
(-300 -1000);
PAINT MONO (-300 -1000);
DISPLAY INVISIBLE (-300 -1000);
FORCEPROP 1 LAST PACK_TYPE 0402LF
J 0
(-475 -850);
DISPLAY 0.638298 (-475 -850);
DISPLAY INVISIBLE (-475 -850);
FORCEPROP 1 LAST WATTAGE 1/16W
J 2
(-100 -850);
DISPLAY 0.638298 (-100 -850);
DISPLAY INVISIBLE (-100 -850);
FORCEPROP 1 LAST PATH I59
J 0
(-350 -850);
DISPLAY 0.978723 (-350 -850);
PAINT WHITE (-350 -850);
DISPLAY INVISIBLE (-350 -850);
FORCEPROP 2 LAST CDS_LOCATION R1413
J 0
(-350 -800);
DISPLAY 1.021277 (-350 -800);
DISPLAY INVISIBLE (-350 -800);
FORCEPROP 2 LAST $SEC 1
J 0
(-350 -800);
DISPLAY 0.680851 (-350 -800);
PAINT MONO (-350 -800);
DISPLAY INVISIBLE (-350 -800);
FORCEPROP 2 LAST CDS_SEC 1
J 0
(-350 -800);
DISPLAY 1.021277 (-350 -800);
DISPLAY INVISIBLE (-350 -800);
FORCEADD Q_RES..1
(-300 3550);
FORCEPROP 1 LAST PART_NUMBER CS22002FB07
J 0
(-475 3650);
DISPLAY 0.638298 (-475 3650);
DISPLAY INVISIBLE (-475 3650);
FORCEPROP 1 LAST TOLERANCE 1%
J 0
(-100 3550);
DISPLAY 0.638298 (-100 3550);
FORCEPROP 1 LAST MATERIAL CHIP
J 0
(0 3550);
DISPLAY 0.638298 (0 3550);
FORCEPROP 1 LAST VALUE 2K
J 2
(-125 3550);
DISPLAY 0.638298 (-125 3550);
FORCEPROP 1 LAST $LOCATION R1418
J 0
(-625 3550);
DISPLAY 0.787234 (-625 3550);
FORCEPROP 1 LASTPIN (-400 3550) $PN 1
J 0
(-388 3562);
DISPLAY 0.787234 (-388 3562);
FORCEPROP 1 LASTPIN (-200 3550) $PN 2
J 0
(-238 3562);
DISPLAY 0.787234 (-238 3562);
FORCEPROP 2 LAST CDS_LIB pure_quanta
J 0
(-300 3550);
PAINT MONO (-300 3550);
DISPLAY INVISIBLE (-300 3550);
FORCEPROP 1 LAST WATTAGE 1/16W
J 2
(-100 3700);
DISPLAY 0.638298 (-100 3700);
DISPLAY INVISIBLE (-100 3700);
FORCEPROP 1 LAST PACK_TYPE 0402LF
J 0
(-475 3700);
DISPLAY 0.638298 (-475 3700);
DISPLAY INVISIBLE (-475 3700);
FORCEPROP 1 LAST PATH I6
J 0
(-350 3700);
DISPLAY 0.978723 (-350 3700);
PAINT WHITE (-350 3700);
DISPLAY INVISIBLE (-350 3700);
FORCEPROP 2 LAST CDS_LOCATION R1418
J 0
(-350 3750);
DISPLAY 1.021277 (-350 3750);
DISPLAY INVISIBLE (-350 3750);
FORCEPROP 2 LAST $SEC 1
J 0
(-350 3750);
DISPLAY 0.680851 (-350 3750);
PAINT MONO (-350 3750);
DISPLAY INVISIBLE (-350 3750);
FORCEPROP 2 LAST CDS_SEC 1
J 0
(-350 3750);
DISPLAY 1.021277 (-350 3750);
DISPLAY INVISIBLE (-350 3750);
FORCEADD OFFPAGE..1
(-2200 50);
FORCEPROP 2 LAST $XR1 222 
J 0
(-2572 50);
DISPLAY 0.638298 (-2572 50);
PAINT MONO (-2572 50);
FORCEPROP 2 LAST $XR0 214 
J 0
(-2452 50);
DISPLAY 0.638298 (-2452 50);
PAINT MONO (-2452 50);
FORCEPROP 2 LAST CDS_LIB standard
J 0
(-2200 50);
PAINT MONO (-2200 50);
DISPLAY INVISIBLE (-2200 50);
FORCEPROP 1 LAST OFFPAGE TRUE
J 0
(-1875 -75);
DISPLAY 0.872340 (-1875 -75);
PAINT GREEN (-1875 -75);
DISPLAY INVISIBLE (-1875 -75);
FORCEPROP 1 LAST COMMENT_BODY TRUE
J 0
(-2075 -50);
DISPLAY 0.872340 (-2075 -50);
PAINT GREEN (-2075 -50);
DISPLAY INVISIBLE (-2075 -50);
FORCEPROP 2 LAST PATH I60
J 0
(-2500 100);
DISPLAY 1.021277 (-2500 100);
DISPLAY INVISIBLE (-2500 100);
FORCEADD OFFPAGE..1
(-2200 -250);
FORCEPROP 2 LAST $XR1 222 
J 0
(-2572 -250);
DISPLAY 0.638298 (-2572 -250);
PAINT MONO (-2572 -250);
FORCEPROP 2 LAST $XR0 214 
J 0
(-2452 -250);
DISPLAY 0.638298 (-2452 -250);
PAINT MONO (-2452 -250);
FORCEPROP 2 LAST CDS_LIB standard
J 0
(-2200 -250);
PAINT MONO (-2200 -250);
DISPLAY INVISIBLE (-2200 -250);
FORCEPROP 1 LAST OFFPAGE TRUE
J 0
(-1875 -375);
DISPLAY 0.872340 (-1875 -375);
PAINT GREEN (-1875 -375);
DISPLAY INVISIBLE (-1875 -375);
FORCEPROP 1 LAST COMMENT_BODY TRUE
J 0
(-2075 -350);
DISPLAY 0.872340 (-2075 -350);
PAINT GREEN (-2075 -350);
DISPLAY INVISIBLE (-2075 -350);
FORCEPROP 2 LAST PATH I61
J 0
(-2500 -200);
DISPLAY 1.021277 (-2500 -200);
DISPLAY INVISIBLE (-2500 -200);
FORCEADD OFFPAGE..1
(-2200 -400);
FORCEPROP 2 LAST $XR1 222 
J 0
(-2572 -400);
DISPLAY 0.638298 (-2572 -400);
PAINT MONO (-2572 -400);
FORCEPROP 2 LAST $XR0 214 
J 0
(-2452 -400);
DISPLAY 0.638298 (-2452 -400);
PAINT MONO (-2452 -400);
FORCEPROP 2 LAST CDS_LIB standard
J 0
(-2200 -400);
PAINT MONO (-2200 -400);
DISPLAY INVISIBLE (-2200 -400);
FORCEPROP 1 LAST OFFPAGE TRUE
J 0
(-1875 -525);
DISPLAY 0.872340 (-1875 -525);
PAINT GREEN (-1875 -525);
DISPLAY INVISIBLE (-1875 -525);
FORCEPROP 1 LAST COMMENT_BODY TRUE
J 0
(-2075 -500);
DISPLAY 0.872340 (-2075 -500);
PAINT GREEN (-2075 -500);
DISPLAY INVISIBLE (-2075 -500);
FORCEPROP 2 LAST PATH I62
J 0
(-2500 -350);
DISPLAY 1.021277 (-2500 -350);
DISPLAY INVISIBLE (-2500 -350);
FORCEADD OFFPAGE..1
(-2200 -550);
FORCEPROP 2 LAST $XR1 222 
J 0
(-2572 -550);
DISPLAY 0.638298 (-2572 -550);
PAINT MONO (-2572 -550);
FORCEPROP 2 LAST $XR0 214 
J 0
(-2452 -550);
DISPLAY 0.638298 (-2452 -550);
PAINT MONO (-2452 -550);
FORCEPROP 2 LAST CDS_LIB standard
J 0
(-2200 -550);
PAINT MONO (-2200 -550);
DISPLAY INVISIBLE (-2200 -550);
FORCEPROP 1 LAST OFFPAGE TRUE
J 0
(-1875 -675);
DISPLAY 0.872340 (-1875 -675);
PAINT GREEN (-1875 -675);
DISPLAY INVISIBLE (-1875 -675);
FORCEPROP 1 LAST COMMENT_BODY TRUE
J 0
(-2075 -650);
DISPLAY 0.872340 (-2075 -650);
PAINT GREEN (-2075 -650);
DISPLAY INVISIBLE (-2075 -650);
FORCEPROP 2 LAST PATH I63
J 0
(-2500 -500);
DISPLAY 1.021277 (-2500 -500);
DISPLAY INVISIBLE (-2500 -500);
FORCEADD OFFPAGE..1
(-2200 -700);
FORCEPROP 2 LAST $XR1 222 
J 0
(-2572 -700);
DISPLAY 0.638298 (-2572 -700);
PAINT MONO (-2572 -700);
FORCEPROP 2 LAST $XR0 214 
J 0
(-2452 -700);
DISPLAY 0.638298 (-2452 -700);
PAINT MONO (-2452 -700);
FORCEPROP 2 LAST CDS_LIB standard
J 0
(-2200 -700);
PAINT MONO (-2200 -700);
DISPLAY INVISIBLE (-2200 -700);
FORCEPROP 1 LAST OFFPAGE TRUE
J 0
(-1875 -825);
DISPLAY 0.872340 (-1875 -825);
PAINT GREEN (-1875 -825);
DISPLAY INVISIBLE (-1875 -825);
FORCEPROP 1 LAST COMMENT_BODY TRUE
J 0
(-2075 -800);
DISPLAY 0.872340 (-2075 -800);
PAINT GREEN (-2075 -800);
DISPLAY INVISIBLE (-2075 -800);
FORCEPROP 2 LAST PATH I64
J 0
(-2500 -650);
DISPLAY 1.021277 (-2500 -650);
DISPLAY INVISIBLE (-2500 -650);
FORCEADD OFFPAGE..1
(-2200 -1150);
FORCEPROP 2 LAST $XR1 296 
J 0
(-2572 -1150);
DISPLAY 0.638298 (-2572 -1150);
PAINT MONO (-2572 -1150);
FORCEPROP 2 LAST $XR0 214 
J 0
(-2452 -1150);
DISPLAY 0.638298 (-2452 -1150);
PAINT MONO (-2452 -1150);
FORCEPROP 2 LAST CDS_LIB standard
J 0
(-2200 -1150);
PAINT MONO (-2200 -1150);
DISPLAY INVISIBLE (-2200 -1150);
FORCEPROP 1 LAST OFFPAGE TRUE
J 0
(-1875 -1275);
DISPLAY 0.872340 (-1875 -1275);
PAINT GREEN (-1875 -1275);
DISPLAY INVISIBLE (-1875 -1275);
FORCEPROP 1 LAST COMMENT_BODY TRUE
J 0
(-2075 -1250);
DISPLAY 0.872340 (-2075 -1250);
PAINT GREEN (-2075 -1250);
DISPLAY INVISIBLE (-2075 -1250);
FORCEPROP 2 LAST PATH I65
J 0
(-2500 -1100);
DISPLAY 1.021277 (-2500 -1100);
DISPLAY INVISIBLE (-2500 -1100);
FORCEADD Q_RES..1
(-300 2950);
FORCEPROP 1 LAST PART_NUMBER CS22002FB07
J 0
(-475 3050);
DISPLAY 0.638298 (-475 3050);
DISPLAY INVISIBLE (-475 3050);
FORCEPROP 1 LAST TOLERANCE 1%
J 0
(-100 2950);
DISPLAY 0.638298 (-100 2950);
FORCEPROP 1 LAST MATERIAL CHIP
J 0
(0 2950);
DISPLAY 0.638298 (0 2950);
FORCEPROP 1 LAST VALUE 2K
J 2
(-125 2950);
DISPLAY 0.638298 (-125 2950);
FORCEPROP 1 LAST $LOCATION R4622
J 0
(-625 2950);
DISPLAY 0.787234 (-625 2950);
FORCEPROP 1 LASTPIN (-400 2950) $PN 1
J 0
(-388 2962);
DISPLAY 0.787234 (-388 2962);
PAINT MONO (-388 2962);
FORCEPROP 1 LASTPIN (-200 2950) $PN 2
J 0
(-238 2962);
DISPLAY 0.787234 (-238 2962);
PAINT MONO (-238 2962);
FORCEPROP 1 LAST WATTAGE 1/16W
J 2
(-100 3100);
DISPLAY 0.638298 (-100 3100);
DISPLAY INVISIBLE (-100 3100);
FORCEPROP 1 LAST PACK_TYPE 0402LF
J 0
(-475 3100);
DISPLAY 0.638298 (-475 3100);
DISPLAY INVISIBLE (-475 3100);
FORCEPROP 2 LAST CDS_LIB pure_quanta
J 0
(-300 2950);
DISPLAY INVISIBLE (-300 2950);
FORCEPROP 1 LAST PATH I66
J 0
(-350 3100);
DISPLAY 0.978723 (-350 3100);
PAINT WHITE (-350 3100);
DISPLAY INVISIBLE (-350 3100);
FORCEPROP 0 LAST CDS_LOCATION R4622
J 0
(0 3000);
DISPLAY 1.021277 (0 3000);
DISPLAY INVISIBLE (0 3000);
FORCEPROP 0 LAST $SEC 1
J 0
(0 3000);
DISPLAY 0.680851 (0 3000);
PAINT MONO (0 3000);
DISPLAY INVISIBLE (0 3000);
FORCEPROP 0 LAST CDS_SEC 1
J 0
(0 3000);
DISPLAY 1.021277 (0 3000);
DISPLAY INVISIBLE (0 3000);
FORCEADD OFFPAGE..1
(-2200 2950);
FORCEPROP 2 LAST $XR1 223 
J 0
(-2572 2950);
DISPLAY 0.638298 (-2572 2950);
PAINT MONO (-2572 2950);
FORCEPROP 2 LAST $XR0 214 
J 0
(-2452 2950);
DISPLAY 0.638298 (-2452 2950);
PAINT MONO (-2452 2950);
FORCEPROP 2 LAST CDS_LIB standard
J 0
(-2200 2950);
DISPLAY INVISIBLE (-2200 2950);
FORCEPROP 1 LAST OFFPAGE TRUE
J 0
(-1875 2825);
DISPLAY 0.872340 (-1875 2825);
PAINT GREEN (-1875 2825);
DISPLAY INVISIBLE (-1875 2825);
FORCEPROP 1 LAST COMMENT_BODY TRUE
J 0
(-2075 2850);
DISPLAY 0.872340 (-2075 2850);
PAINT GREEN (-2075 2850);
DISPLAY INVISIBLE (-2075 2850);
FORCEPROP 2 LAST PATH I67
J 0
(-2150 3025);
DISPLAY 1.021277 (-2150 3025);
DISPLAY INVISIBLE (-2150 3025);
FORCEADD Q_RES..1
(-300 3700);
FORCEPROP 1 LAST PART_NUMBER CS22002FB07
J 0
(-475 3800);
DISPLAY 0.638298 (-475 3800);
DISPLAY INVISIBLE (-475 3800);
FORCEPROP 1 LAST TOLERANCE 1%
J 0
(-100 3700);
DISPLAY 0.638298 (-100 3700);
FORCEPROP 1 LAST MATERIAL CHIP
J 0
(0 3700);
DISPLAY 0.638298 (0 3700);
FORCEPROP 1 LAST VALUE 2K
J 2
(-125 3700);
DISPLAY 0.638298 (-125 3700);
FORCEPROP 1 LAST $LOCATION R1417
J 0
(-625 3700);
DISPLAY 0.787234 (-625 3700);
FORCEPROP 1 LASTPIN (-400 3700) $PN 1
J 0
(-388 3712);
DISPLAY 0.787234 (-388 3712);
FORCEPROP 1 LASTPIN (-200 3700) $PN 2
J 0
(-238 3712);
DISPLAY 0.787234 (-238 3712);
FORCEPROP 2 LAST CDS_LIB pure_quanta
J 0
(-300 3700);
PAINT MONO (-300 3700);
DISPLAY INVISIBLE (-300 3700);
FORCEPROP 1 LAST PACK_TYPE 0402LF
J 0
(-475 3850);
DISPLAY 0.638298 (-475 3850);
DISPLAY INVISIBLE (-475 3850);
FORCEPROP 1 LAST WATTAGE 1/16W
J 2
(-100 3850);
DISPLAY 0.638298 (-100 3850);
DISPLAY INVISIBLE (-100 3850);
FORCEPROP 1 LAST PATH I7
J 0
(-350 3850);
DISPLAY 0.978723 (-350 3850);
PAINT WHITE (-350 3850);
DISPLAY INVISIBLE (-350 3850);
FORCEPROP 2 LAST CDS_LOCATION R1417
J 0
(-350 3900);
DISPLAY 1.021277 (-350 3900);
DISPLAY INVISIBLE (-350 3900);
FORCEPROP 2 LAST $SEC 1
J 0
(-350 3900);
DISPLAY 0.680851 (-350 3900);
PAINT MONO (-350 3900);
DISPLAY INVISIBLE (-350 3900);
FORCEPROP 2 LAST CDS_SEC 1
J 0
(-350 3900);
DISPLAY 1.021277 (-350 3900);
DISPLAY INVISIBLE (-350 3900);
FORCEADD Q_RES..1
(-300 3400);
FORCEPROP 1 LAST PART_NUMBER CS22002FB07
J 0
(-475 3500);
DISPLAY 0.638298 (-475 3500);
DISPLAY INVISIBLE (-475 3500);
FORCEPROP 1 LAST TOLERANCE 1%
J 0
(-100 3400);
DISPLAY 0.638298 (-100 3400);
FORCEPROP 1 LAST VALUE 2K
J 2
(-125 3400);
DISPLAY 0.638298 (-125 3400);
FORCEPROP 1 LAST MATERIAL CHIP
J 0
(0 3400);
DISPLAY 0.638298 (0 3400);
FORCEPROP 1 LAST $LOCATION R1419
J 0
(-625 3400);
DISPLAY 0.787234 (-625 3400);
FORCEPROP 1 LASTPIN (-400 3400) $PN 1
J 0
(-388 3412);
DISPLAY 0.787234 (-388 3412);
FORCEPROP 1 LASTPIN (-200 3400) $PN 2
J 0
(-238 3412);
DISPLAY 0.787234 (-238 3412);
FORCEPROP 2 LAST CDS_LIB pure_quanta
J 0
(-300 3400);
PAINT MONO (-300 3400);
DISPLAY INVISIBLE (-300 3400);
FORCEPROP 1 LAST PACK_TYPE 0402LF
J 0
(-475 3550);
DISPLAY 0.638298 (-475 3550);
DISPLAY INVISIBLE (-475 3550);
FORCEPROP 1 LAST WATTAGE 1/16W
J 2
(-100 3550);
DISPLAY 0.638298 (-100 3550);
DISPLAY INVISIBLE (-100 3550);
FORCEPROP 1 LAST PATH I8
J 0
(-350 3550);
DISPLAY 0.978723 (-350 3550);
PAINT WHITE (-350 3550);
DISPLAY INVISIBLE (-350 3550);
FORCEPROP 2 LAST CDS_LOCATION R1419
J 0
(-350 3600);
DISPLAY 1.021277 (-350 3600);
DISPLAY INVISIBLE (-350 3600);
FORCEPROP 2 LAST $SEC 1
J 0
(-350 3600);
DISPLAY 0.680851 (-350 3600);
PAINT MONO (-350 3600);
DISPLAY INVISIBLE (-350 3600);
FORCEPROP 2 LAST CDS_SEC 1
J 0
(-350 3600);
DISPLAY 1.021277 (-350 3600);
DISPLAY INVISIBLE (-350 3600);
FORCEADD Q_RES..1
(-300 3250);
FORCEPROP 1 LAST PART_NUMBER CS22002FB07
J 0
(-475 3350);
DISPLAY 0.638298 (-475 3350);
DISPLAY INVISIBLE (-475 3350);
FORCEPROP 1 LAST TOLERANCE 1%
J 0
(-100 3250);
DISPLAY 0.638298 (-100 3250);
FORCEPROP 1 LAST VALUE 2K
J 2
(-125 3250);
DISPLAY 0.638298 (-125 3250);
FORCEPROP 1 LAST MATERIAL CHIP
J 0
(0 3250);
DISPLAY 0.638298 (0 3250);
FORCEPROP 1 LAST $LOCATION R1420
J 0
(-625 3250);
DISPLAY 0.787234 (-625 3250);
FORCEPROP 1 LASTPIN (-400 3250) $PN 1
J 0
(-388 3262);
DISPLAY 0.787234 (-388 3262);
FORCEPROP 1 LASTPIN (-200 3250) $PN 2
J 0
(-238 3262);
DISPLAY 0.787234 (-238 3262);
FORCEPROP 2 LAST CDS_LIB pure_quanta
J 0
(-300 3250);
PAINT MONO (-300 3250);
DISPLAY INVISIBLE (-300 3250);
FORCEPROP 1 LAST PACK_TYPE 0402LF
J 0
(-475 3400);
DISPLAY 0.638298 (-475 3400);
DISPLAY INVISIBLE (-475 3400);
FORCEPROP 1 LAST WATTAGE 1/16W
J 2
(-100 3400);
DISPLAY 0.638298 (-100 3400);
DISPLAY INVISIBLE (-100 3400);
FORCEPROP 1 LAST PATH I9
J 0
(-350 3400);
DISPLAY 0.978723 (-350 3400);
PAINT WHITE (-350 3400);
DISPLAY INVISIBLE (-350 3400);
FORCEPROP 2 LAST CDS_LOCATION R1420
J 0
(-350 3450);
DISPLAY 1.021277 (-350 3450);
DISPLAY INVISIBLE (-350 3450);
FORCEPROP 2 LAST $SEC 1
J 0
(-350 3450);
DISPLAY 0.680851 (-350 3450);
PAINT MONO (-350 3450);
DISPLAY INVISIBLE (-350 3450);
FORCEPROP 2 LAST CDS_SEC 1
J 0
(-350 3450);
DISPLAY 1.021277 (-350 3450);
DISPLAY INVISIBLE (-350 3450);
FORCEADD QUANTA_TITLE_BLOCK_C..1
(5775 -2000);
FORCEPROP 0 LAST CDS_CON_LAST_MODIFIED Fri Aug 25 14:03:40 2023
J 0
(3890 -1985);
PAINT MONO (3890 -1985);
DISPLAY INVISIBLE (3890 -1985);
FORCEPROP 2 LAST CUSTOM_TXT_CDS <XR_PAGE_TITLE>
J 0
(-2115 3250);
DISPLAY 0.638298 (-2115 3250);
PAINT PINK (-2115 3250);
DISPLAY INVISIBLE (-2115 3250);
FORCEPROP 2 LAST CUSTOM_TXT_CDS <CON_LAST_MODIFIED>
J 0
(3890 -1985);
DISPLAY 0.978723 (3890 -1985);
FORCEPROP 2 LAST CUSTOM_TXT_CDS <Q_REV>
J 0
(5591 -1897);
DISPLAY 1.212766 (5591 -1897);
FORCEPROP 2 LAST CUSTOM_TXT_CDS <CON_PAGE_NUM> OF <CON_TOTAL_PAGES>
J 0
(5329 -1982);
DISPLAY 0.978723 (5329 -1982);
FORCEPROP 2 LAST CUSTOM_TXT_CDS <Q_NUMBER>
J 0
(4372 -1897);
DISPLAY 1.212766 (4372 -1897);
FORCEPROP 2 LAST CUSTOM_TXT_CDS <Q_PROJ>
J 0
(3393 -1898);
DISPLAY 1.212766 (3393 -1898);
FORCEPROP 2 LAST CUSTOM_TXT_CDS <NAME_1>
J 0
(2600 -1825);
FORCEPROP 2 LAST CUSTOM_TXT_CDS <NAME_2>
J 0
(2600 -1950);
FORCEPROP 1 LAST Q_TITLE MAIN FPGA / PFR - PU/PD
J 0
(-3566 -1974);
DISPLAY 1.957447 (-3566 -1974);
PAINT GREEN (-3566 -1974);
FORCEPROP 1 LAST Q_DEPT 
J 1
(2012 -1951);
DISPLAY 1.957447 (2012 -1951);
PAINT GREEN (2012 -1951);
FORCEPROP 2 LAST CDS_XR_PAGE_TITLE CR-219 : @S9S_MB_2U_LIB.S9S_MB_2U(SCH_1):PAGE219
J 0
(-2115 3250);
DISPLAY 0.638298 (-2115 3250);
PAINT PINK (-2115 3250);
DISPLAY INVISIBLE (-2115 3250);
FORCEPROP 1 LAST COMMENT_BODY TRUE
J 0
(5787 -2013);
DISPLAY 0.978723 (5787 -2013);
PAINT GREEN (5787 -2013);
DISPLAY INVISIBLE (5787 -2013);
FORCEPROP 2 LAST CDS_LIB pure_quanta
J 0
(5775 -2000);
PAINT MONO (5775 -2000);
DISPLAY INVISIBLE (5775 -2000);
FORCEPROP 1 LAST CDS_LMAN_SYM_OUTLINE -9475,6775,100,-125
J 0
(5775 -2000);
DISPLAY 0.468085 (5775 -2000);
PAINT GREEN (5775 -2000);
DISPLAY INVISIBLE (5775 -2000);
FORCEPROP 2 LAST PAGE_BORDER TRUE
J 0
(-2115 3250);
DISPLAY 0.638298 (-2115 3250);
PAINT PINK (-2115 3250);
DISPLAY INVISIBLE (-2115 3250);
FORCEADD DNS..2
(-275 800);
PAINT RED (-275 800);
FORCEPROP 2 LAST CDS_LIB mstr_misc
J 0
(-275 800);
DISPLAY INVISIBLE (-275 800);
FORCEPROP 1 LAST COMMENT_BODY TRUE
J 0
(-275 800);
DISPLAY INVISIBLE (-275 800);
FORCEADD DNS..2
(-275 950);
PAINT RED (-275 950);
FORCEPROP 2 LAST CDS_LIB mstr_misc
J 0
(-275 950);
DISPLAY INVISIBLE (-275 950);
FORCEPROP 1 LAST COMMENT_BODY TRUE
J 0
(-275 950);
DISPLAY INVISIBLE (-275 950);
FORCEADD DNS..2
(-275 1625);
PAINT RED (-275 1625);
FORCEPROP 2 LAST CDS_LIB mstr_misc
J 0
(-275 1625);
DISPLAY INVISIBLE (-275 1625);
FORCEPROP 1 LAST COMMENT_BODY TRUE
J 0
(-275 1625);
DISPLAY INVISIBLE (-275 1625);
FORCEADD DNS..2
(-275 1925);
PAINT RED (-275 1925);
FORCEPROP 2 LAST CDS_LIB mstr_misc
J 0
(-275 1925);
DISPLAY INVISIBLE (-275 1925);
FORCEPROP 1 LAST COMMENT_BODY TRUE
J 0
(-275 1925);
DISPLAY INVISIBLE (-275 1925);
FORCEADD DNS..2
(-275 2400);
PAINT RED (-275 2400);
FORCEPROP 2 LAST CDS_LIB mstr_misc
J 0
(-275 2400);
DISPLAY INVISIBLE (-275 2400);
FORCEPROP 1 LAST COMMENT_BODY TRUE
J 0
(-275 2400);
DISPLAY INVISIBLE (-275 2400);
FORCEADD DNS..2
(-275 1775);
PAINT RED (-275 1775);
FORCEPROP 2 LAST CDS_LIB mstr_misc
J 0
(-275 1775);
DISPLAY INVISIBLE (-275 1775);
FORCEPROP 1 LAST COMMENT_BODY TRUE
J 0
(-275 1775);
DISPLAY INVISIBLE (-275 1775);
FORCEADD DNS..2
(-275 2075);
PAINT RED (-275 2075);
FORCEPROP 2 LAST CDS_LIB mstr_misc
J 0
(-275 2075);
DISPLAY INVISIBLE (-275 2075);
FORCEPROP 1 LAST COMMENT_BODY TRUE
J 0
(-275 2075);
DISPLAY INVISIBLE (-275 2075);
FORCEADD DNS..2
(-275 2225);
PAINT RED (-275 2225);
FORCEPROP 2 LAST CDS_LIB mstr_misc
J 0
(-275 2225);
DISPLAY INVISIBLE (-275 2225);
FORCEPROP 1 LAST COMMENT_BODY TRUE
J 0
(-275 2225);
DISPLAY INVISIBLE (-275 2225);
FORCEADD DNS..2
(-275 2525);
PAINT RED (-275 2525);
FORCEPROP 2 LAST CDS_LIB mstr_misc
J 0
(-275 2525);
DISPLAY INVISIBLE (-275 2525);
FORCEPROP 1 LAST COMMENT_BODY TRUE
J 0
(-275 2525);
DISPLAY INVISIBLE (-275 2525);
FORCEADD DNS..2
(-275 2675);
PAINT RED (-275 2675);
FORCEPROP 2 LAST CDS_LIB mstr_misc
J 0
(-275 2675);
DISPLAY INVISIBLE (-275 2675);
FORCEPROP 1 LAST COMMENT_BODY TRUE
J 0
(-275 2675);
DISPLAY INVISIBLE (-275 2675);
FORCEADD DNS..2
(-275 3875);
PAINT RED (-275 3875);
FORCEPROP 2 LAST CDS_LIB mstr_misc
J 0
(-275 3875);
DISPLAY INVISIBLE (-275 3875);
FORCEPROP 1 LAST COMMENT_BODY TRUE
J 0
(-275 3875);
DISPLAY INVISIBLE (-275 3875);
FORCEADD DNS..2
(-275 4000);
PAINT RED (-275 4000);
FORCEPROP 2 LAST CDS_LIB mstr_misc
J 0
(-275 4000);
DISPLAY INVISIBLE (-275 4000);
FORCEPROP 1 LAST COMMENT_BODY TRUE
J 0
(-275 4000);
DISPLAY INVISIBLE (-275 4000);
WIRE 16 -1 (250 -1150)(250 -1275);
WIRE 16 -1 (250 -1000)(250 -1150);
WIRE 16 -1 (250 -1150)(-200 -1150);
WIRE 16 -1 (-2150 2950)(-400 2950);
FORCEPROP 0 LAST CDS_PHYS_NET_NAME RST_PERST_SWB_R_N
J 0
(-2125 2992);
PAINT MONO (-2125 2992);
DISPLAY INVISIBLE (-2125 2992);
FORCEPROP 0 LAST SIG_NAME RST_PERST_SWB_N
J 0
(-2010 2960);
DISPLAY 0.872340 (-2010 2960);
PAINT WHITE (-2010 2960);
WIRE 16 -1 (250 4000)(-200 4000);
WIRE 16 -1 (250 3850)(-200 3850);
WIRE 16 -1 (250 3850)(250 4000);
WIRE 16 -1 (250 3700)(-200 3700);
WIRE 16 -1 (250 3700)(250 3850);
WIRE 16 -1 (250 3550)(-200 3550);
WIRE 16 -1 (250 3550)(250 3700);
WIRE 16 -1 (250 3400)(-200 3400);
WIRE 16 -1 (250 3400)(250 3550);
WIRE 16 -1 (250 3250)(-200 3250);
WIRE 16 -1 (250 3250)(250 3400);
WIRE 16 -1 (250 3100)(-200 3100);
WIRE 16 -1 (250 3100)(250 3250);
WIRE 16 -1 (-200 2950)(250 2950);
WIRE 16 -1 (250 3100)(250 2950);
WIRE 16 -1 (250 2675)(-200 2675);
WIRE 16 -1 (250 2675)(250 2950);
WIRE 16 -1 (250 2525)(-200 2525);
WIRE 16 -1 (250 2675)(250 2525);
WIRE 16 -1 (250 2375)(-200 2375);
WIRE 16 -1 (250 2525)(250 2375);
WIRE 16 -1 (250 2225)(-200 2225);
WIRE 16 -1 (250 2375)(250 2225);
WIRE 16 -1 (250 2075)(-200 2075);
WIRE 16 -1 (250 2225)(250 2075);
WIRE 16 -1 (250 1925)(-200 1925);
WIRE 16 -1 (250 2075)(250 1925);
WIRE 16 -1 (250 1775)(-200 1775);
WIRE 16 -1 (250 1925)(250 1775);
WIRE 16 -1 (250 1625)(-200 1625);
WIRE 16 -1 (250 1775)(250 1625);
WIRE 16 -1 (250 1250)(-200 1250);
WIRE 16 -1 (250 1625)(250 1250);
WIRE 16 -1 (250 1100)(-200 1100);
WIRE 16 -1 (250 1100)(250 1250);
WIRE 16 -1 (250 950)(-200 950);
WIRE 16 -1 (250 950)(250 1100);
WIRE 16 -1 (250 800)(-200 800);
WIRE 16 -1 (250 800)(250 950);
WIRE 16 -1 (250 650)(-200 650);
WIRE 16 -1 (250 800)(250 650);
WIRE 16 -1 (250 500)(-200 500);
WIRE 16 -1 (250 500)(250 650);
WIRE 16 -1 (250 350)(-200 350);
WIRE 16 -1 (250 350)(250 500);
WIRE 16 -1 (250 200)(-200 200);
WIRE 16 -1 (250 200)(250 350);
WIRE 16 -1 (250 50)(-200 50);
WIRE 16 -1 (250 50)(250 200);
WIRE 16 -1 (250 -100)(-200 -100);
WIRE 16 -1 (250 -100)(250 50);
WIRE 16 -1 (250 -250)(-200 -250);
WIRE 16 -1 (250 -250)(250 -100);
WIRE 16 -1 (250 -400)(-200 -400);
WIRE 16 -1 (250 -400)(250 -250);
WIRE 16 -1 (250 -550)(-200 -550);
WIRE 16 -1 (250 -550)(250 -400);
WIRE 16 -1 (250 -700)(-200 -700);
WIRE 16 -1 (250 -700)(250 -550);
WIRE 16 -1 (250 -850)(-200 -850);
WIRE 16 -1 (250 -850)(250 -700);
WIRE 16 -1 (250 -1000)(-200 -1000);
WIRE 16 -1 (250 -1000)(250 -850);
WIRE 16 -1 (-2150 -1000)(-400 -1000);
FORCEPROP 2 LAST SIG_NAME FM_PVCCD_HV_CPU0_EN
J 0
(-2010 -990);
DISPLAY 0.851064 (-2010 -990);
PAINT WHITE (-2010 -990);
WIRE 16 -1 (-2150 50)(-400 50);
FORCEPROP 2 LAST SIG_NAME FM_PVCCIN_CPU1_R_EN
J 0
(-2010 60);
DISPLAY 0.851064 (-2010 60);
PAINT WHITE (-2010 60);
WIRE 16 -1 (-2150 2525)(-400 2525);
FORCEPROP 0 LAST CDS_PHYS_NET_NAME PWRGD_CPU1_LVC1_R
J 0
(-2010 2575);
PAINT MONO (-2010 2575);
DISPLAY INVISIBLE (-2010 2575);
FORCEPROP 2 LAST SIG_NAME PWRGD_DRAMPWRGD_CPU0_CD_R_LVC1
J 0
(-2010 2535);
DISPLAY 0.851064 (-2010 2535);
PAINT WHITE (-2010 2535);
WIRE 16 -1 (-2150 3850)(-400 3850);
FORCEPROP 0 LAST CDS_PHYS_NET_NAME RST_CPU1_LVC1_R_N
J 0
(-2010 3900);
PAINT MONO (-2010 3900);
DISPLAY INVISIBLE (-2010 3900);
FORCEPROP 2 LAST SIG_NAME RST_CPU1_LVC1_R_N
J 0
(-2010 3860);
DISPLAY 0.851064 (-2010 3860);
PAINT WHITE (-2010 3860);
WIRE 16 -1 (-2150 650)(-400 650);
FORCEPROP 2 LAST SIG_NAME PWRGD_SYS_PWROK
J 0
(-2010 660);
DISPLAY 0.851064 (-2010 660);
PAINT WHITE (-2010 660);
WIRE 16 -1 (-2150 1250)(-400 1250);
FORCEPROP 0 LAST CDS_PHYS_NET_NAME FM_PLD_CLK_25M_R_EN
J 0
(-2010 1300);
PAINT MONO (-2010 1300);
DISPLAY INVISIBLE (-2010 1300);
FORCEPROP 2 LAST SIG_NAME FM_PLD_CLK_25M_R_EN
J 0
(-2010 1260);
DISPLAY 0.851064 (-2010 1260);
PAINT WHITE (-2010 1260);
WIRE 16 -1 (-2150 950)(-400 950);
FORCEPROP 0 LAST CDS_PHYS_NET_NAME PWRGD_CPU0_LVC1_R
J 0
(-2010 1000);
PAINT MONO (-2010 1000);
DISPLAY INVISIBLE (-2010 1000);
FORCEPROP 2 LAST SIG_NAME PWRGD_CPU0_LVC1_R
J 0
(-2010 960);
DISPLAY 0.851064 (-2010 960);
PAINT WHITE (-2010 960);
WIRE 16 -1 (-2150 1100)(-400 1100);
FORCEPROP 0 LAST CDS_PHYS_NET_NAME FM_AUX_SW_EN
J 0
(-2010 1150);
PAINT MONO (-2010 1150);
DISPLAY INVISIBLE (-2010 1150);
FORCEPROP 2 LAST SIG_NAME FM_AUX_SW_EN
J 0
(-2010 1110);
DISPLAY 0.851064 (-2010 1110);
PAINT WHITE (-2010 1110);
WIRE 16 -1 (-2150 2075)(-400 2075);
FORCEPROP 0 LAST CDS_PHYS_NET_NAME RST_SRST_BMC_PLD_N
J 0
(-2010 2125);
PAINT MONO (-2010 2125);
DISPLAY INVISIBLE (-2010 2125);
FORCEPROP 2 LAST SIG_NAME PWRGD_DRAMPWRGD_CPU1_AB_R_LVC1
J 0
(-2010 2085);
DISPLAY 0.851064 (-2010 2085);
PAINT WHITE (-2010 2085);
WIRE 16 -1 (-2150 1925)(-400 1925);
FORCEPROP 0 LAST CDS_PHYS_NET_NAME PWRGD_CPU1_LVC1_R
J 0
(-2010 1975);
PAINT MONO (-2010 1975);
DISPLAY INVISIBLE (-2010 1975);
FORCEPROP 2 LAST SIG_NAME PWRGD_DRAMPWRGD_CPU1_CD_R_LVC1
J 0
(-2010 1935);
DISPLAY 0.851064 (-2010 1935);
PAINT WHITE (-2010 1935);
WIRE 16 -1 (-2150 800)(-400 800);
FORCEPROP 2 LAST SIG_NAME PWRGD_CPU1_LVC1_R
J 0
(-2010 810);
DISPLAY 0.851064 (-2010 810);
PAINT WHITE (-2010 810);
WIRE 16 -1 (-2150 500)(-400 500);
FORCEPROP 2 LAST SIG_NAME PWRGD_PCH_PWROK
J 0
(-2010 510);
DISPLAY 0.851064 (-2010 510);
PAINT WHITE (-2010 510);
WIRE 16 -1 (-2150 350)(-400 350);
FORCEPROP 2 LAST SIG_NAME FM_PCH_P1V8_AUX_EN
J 0
(-2010 360);
DISPLAY 0.851064 (-2010 360);
PAINT WHITE (-2010 360);
WIRE 16 -1 (-2150 200)(-400 200);
FORCEPROP 2 LAST SIG_NAME FM_PVCCIN_CPU0_R_EN
J 0
(-2010 210);
DISPLAY 0.851064 (-2010 210);
PAINT WHITE (-2010 210);
WIRE 16 -1 (-2150 -850)(-400 -850);
FORCEPROP 2 LAST SIG_NAME FM_PVCCFA_EHV_FIVRA_CPU1_R_EN
J 0
(-2010 -840);
DISPLAY 0.851064 (-2010 -840);
PAINT WHITE (-2010 -840);
WIRE 16 -1 (-2150 -1150)(-400 -1150);
FORCEPROP 2 LAST SIG_NAME FM_PVCCD_HV_CPU1_EN
J 0
(-2010 -1140);
DISPLAY 0.851064 (-2010 -1140);
PAINT WHITE (-2010 -1140);
WIRE 16 -1 (-2150 -700)(-400 -700);
FORCEPROP 2 LAST SIG_NAME FM_PVCCFA_EHV_FIVRA_CPU0_R_EN
J 0
(-2010 -690);
DISPLAY 0.851064 (-2010 -690);
PAINT WHITE (-2010 -690);
WIRE 16 -1 (-2150 -550)(-400 -550);
FORCEPROP 2 LAST SIG_NAME FM_PVCCFA_EHV_CPU1_R_EN
J 0
(-2010 -540);
DISPLAY 0.851064 (-2010 -540);
PAINT WHITE (-2010 -540);
WIRE 16 -1 (-2150 -400)(-400 -400);
FORCEPROP 2 LAST SIG_NAME FM_PVCCFA_EHV_CPU0_R_EN
J 0
(-2010 -390);
DISPLAY 0.851064 (-2010 -390);
PAINT WHITE (-2010 -390);
WIRE 16 -1 (-2150 -250)(-400 -250);
FORCEPROP 2 LAST SIG_NAME FM_PVCCINFAON_CPU1_R_EN
J 0
(-2010 -240);
DISPLAY 0.851064 (-2010 -240);
PAINT WHITE (-2010 -240);
WIRE 16 -1 (-2150 -100)(-400 -100);
FORCEPROP 2 LAST SIG_NAME FM_PVCCINFAON_CPU0_R_EN
J 0
(-2010 -90);
DISPLAY 0.851064 (-2010 -90);
PAINT WHITE (-2010 -90);
WIRE 16 -1 (-2150 1625)(-400 1625);
FORCEPROP 0 LAST CDS_PHYS_NET_NAME RST_SRST_BMC_PLD_N
J 0
(-2010 1675);
PAINT MONO (-2010 1675);
DISPLAY INVISIBLE (-2010 1675);
FORCEPROP 2 LAST SIG_NAME PWRGD_DRAMPWRGD_CPU1_GH_R_LVC1
J 0
(-2010 1635);
DISPLAY 0.851064 (-2010 1635);
PAINT WHITE (-2010 1635);
WIRE 16 -1 (-2150 1775)(-400 1775);
FORCEPROP 0 LAST CDS_PHYS_NET_NAME PWRGD_CPU1_LVC1_R
J 0
(-2010 1825);
PAINT MONO (-2010 1825);
DISPLAY INVISIBLE (-2010 1825);
FORCEPROP 2 LAST SIG_NAME PWRGD_DRAMPWRGD_CPU1_EF_R_LVC1
J 0
(-2010 1785);
DISPLAY 0.851064 (-2010 1785);
PAINT WHITE (-2010 1785);
WIRE 16 -1 (-2150 4000)(-400 4000);
FORCEPROP 0 LAST CDS_PHYS_NET_NAME RST_CPU0_LVC1_R_N
J 0
(-2010 4050);
PAINT MONO (-2010 4050);
DISPLAY INVISIBLE (-2010 4050);
FORCEPROP 2 LAST SIG_NAME RST_CPU0_LVC1_R_N
J 0
(-2010 4010);
DISPLAY 0.851064 (-2010 4010);
PAINT WHITE (-2010 4010);
WIRE 16 -1 (-2150 3700)(-400 3700);
FORCEPROP 2 LAST SIG_NAME RST_PCIE_CPU0_DEV_PERST_N
J 0
(-2010 3710);
DISPLAY 0.851064 (-2010 3710);
PAINT WHITE (-2010 3710);
WIRE 16 -1 (-2150 3550)(-400 3550);
FORCEPROP 2 LAST SIG_NAME RST_PCIE_CPU1_DEV_PERST_N
J 0
(-2010 3560);
DISPLAY 0.851064 (-2010 3560);
PAINT WHITE (-2010 3560);
WIRE 16 -1 (-2150 3100)(-400 3100);
FORCEPROP 0 LAST CDS_PHYS_NET_NAME PWRGD_CPU1_LVC1_R
J 0
(-2010 3150);
PAINT MONO (-2010 3150);
DISPLAY INVISIBLE (-2010 3150);
FORCEPROP 2 LAST SIG_NAME RST_RSMRST_PLD_R_N
J 0
(-2010 3110);
DISPLAY 0.851064 (-2010 3110);
PAINT WHITE (-2010 3110);
WIRE 16 -1 (-2150 2225)(-400 2225);
FORCEPROP 0 LAST CDS_PHYS_NET_NAME RST_SRST_BMC_PLD_N
J 0
(-2010 2275);
PAINT MONO (-2010 2275);
DISPLAY INVISIBLE (-2010 2275);
FORCEPROP 2 LAST SIG_NAME PWRGD_DRAMPWRGD_CPU0_GH_R_LVC1
J 0
(-2010 2235);
DISPLAY 0.851064 (-2010 2235);
PAINT WHITE (-2010 2235);
WIRE 16 -1 (-2150 2375)(-400 2375);
FORCEPROP 0 LAST CDS_PHYS_NET_NAME PWRGD_CPU1_LVC1_R
J 0
(-2010 2425);
PAINT MONO (-2010 2425);
DISPLAY INVISIBLE (-2010 2425);
FORCEPROP 2 LAST SIG_NAME PWRGD_DRAMPWRGD_CPU0_EF_R_LVC1
J 0
(-2010 2385);
DISPLAY 0.851064 (-2010 2385);
PAINT WHITE (-2010 2385);
WIRE 16 -1 (-2150 2675)(-400 2675);
FORCEPROP 0 LAST CDS_PHYS_NET_NAME PWRGD_CPU1_LVC1_R
J 0
(-2010 2725);
PAINT MONO (-2010 2725);
DISPLAY INVISIBLE (-2010 2725);
FORCEPROP 2 LAST SIG_NAME PWRGD_DRAMPWRGD_CPU0_AB_R_LVC1
J 0
(-2010 2685);
DISPLAY 0.851064 (-2010 2685);
PAINT WHITE (-2010 2685);
WIRE 16 -1 (-2150 3250)(-400 3250);
FORCEPROP 2 LAST SIG_NAME RST_PLTRST_PLD_B_N
J 0
(-2010 3260);
DISPLAY 0.851064 (-2010 3260);
PAINT WHITE (-2010 3260);
WIRE 16 -1 (-2150 3400)(-400 3400);
FORCEPROP 0 LAST CDS_PHYS_NET_NAME PWRGD_CPU1_LVC1_R
J 0
(-2010 3450);
PAINT MONO (-2010 3450);
DISPLAY INVISIBLE (-2010 3450);
FORCEPROP 2 LAST SIG_NAME RST_PCIE_PCH_DEV_PERST_N
J 0
(-2010 3410);
DISPLAY 0.851064 (-2010 3410);
PAINT WHITE (-2010 3410);
DOT 1 (250 950);
DOT 1 (250 -1150);
DOT 1 (250 -1000);
DOT 1 (250 -700);
DOT 1 (250 -850);
DOT 1 (250 -550);
DOT 1 (250 -400);
DOT 1 (250 -250);
DOT 1 (250 -100);
DOT 1 (250 50);
DOT 1 (250 200);
DOT 1 (250 350);
DOT 1 (250 500);
DOT 1 (250 650);
DOT 1 (250 800);
DOT 1 (250 1100);
DOT 1 (250 1250);
DOT 1 (250 1625);
DOT 1 (250 2075);
DOT 1 (250 2225);
DOT 1 (250 2675);
DOT 1 (250 2525);
DOT 1 (250 3100);
DOT 1 (250 3400);
DOT 1 (250 3250);
DOT 1 (250 3700);
DOT 1 (250 3550);
DOT 1 (250 3850);
DOT 1 (250 2375);
DOT 1 (250 1775);
DOT 1 (250 1925);
DOT 1 (250 2950);
FORCENOTE
20210902 MODIFY FOR GT
(-3300 4325) 0;
DISPLAY LEFT (-3300 4325);
DISPLAY 2.510638 (-3300 4325);
PAINT PINK (-3300 4325);
QUIT
